FILE_TYPE = MACRO_DRAWING;
SET COLOR_WIRE YELLOW;
SET COLOR_PROP ORANGE;
SET COLOR_DOT WHITE;
SET COLOR_ARC YELLOW;
SET COLOR_BODY GREEN;
SET COLOR_NOTE PURPLE;
SET PROP_DISPLAY VALUE;
SET PAGE_NUMBER P151;
FORCEADD SN74AUC2G66DCTR..1
(-6375 5800);
FORCEPROP 1 LAST LOCATION U153
J 0
(-6529 6032);
DISPLAY 0.489362 (-6529 6032);
PAINT SKYBLUE (-6529 6032);
FORCEPROP 0 LAST $SEC 1
J 0
(-6525 6175);
DISPLAY 0.680851 (-6525 6175);
PAINT MONO (-6525 6175);
DISPLAY INVISIBLE (-6525 6175);
FORCEPROP 0 LAST CDS_SEC 1
J 0
(-6525 6175);
DISPLAY 1.021277 (-6525 6175);
DISPLAY INVISIBLE (-6525 6175);
FORCEPROP 0 LASTPIN (-6675 5875) $PN 1
J 2
(-6685 5885);
DISPLAY 0.489362 (-6685 5885);
PAINT MONO (-6685 5885);
FORCEPROP 0 LASTPIN (-6075 5825) $PN 2
J 0
(-6065 5835);
DISPLAY 0.489362 (-6065 5835);
PAINT MONO (-6065 5835);
FORCEPROP 0 LASTPIN (-6675 5825) $PN 7
J 2
(-6685 5835);
DISPLAY 0.489362 (-6685 5835);
PAINT MONO (-6685 5835);
FORCEPROP 0 LASTPIN (-6675 5775) $PN 5
J 2
(-6685 5785);
DISPLAY 0.489362 (-6685 5785);
PAINT MONO (-6685 5785);
FORCEPROP 0 LASTPIN (-6075 5775) $PN 6
J 0
(-6065 5785);
DISPLAY 0.489362 (-6065 5785);
PAINT MONO (-6065 5785);
FORCEPROP 0 LASTPIN (-6675 5725) $PN 3
J 2
(-6685 5735);
DISPLAY 0.489362 (-6685 5735);
PAINT MONO (-6685 5735);
FORCEPROP 0 LASTPIN (-6075 5725) $PN 4
J 0
(-6065 5735);
DISPLAY 0.489362 (-6065 5735);
PAINT MONO (-6065 5735);
FORCEPROP 0 LASTPIN (-6075 5875) $PN 8
J 0
(-6065 5885);
DISPLAY 0.489362 (-6065 5885);
PAINT MONO (-6065 5885);
FORCEPROP 2 LAST PART_TYPE SMLF
J 0
(-6525 6125);
DISPLAY 1.021277 (-6525 6125);
FORCEPROP 2 LAST VALUE SN74AUC2G66DCTR
J 0
(-6525 6075);
DISPLAY 0.489362 (-6525 6075);
PAINT SKYBLUE (-6525 6075);
FORCEPROP 1 LAST MATERIAL IC
J 0
(-6529 5929);
DISPLAY 0.489362 (-6529 5929);
PAINT SKYBLUE (-6529 5929);
FORCEPROP 2 LAST CDS_LIB pure_quanta
J 0
(-6375 5800);
DISPLAY INVISIBLE (-6375 5800);
FORCEPROP 1 LAST NEEDS_NO_SIZE TRUE
J 0
(-6375 5800);
DISPLAY 0.723404 (-6375 5800);
PAINT GREEN (-6375 5800);
DISPLAY INVISIBLE (-6375 5800);
FORCEPROP 1 LAST CDS_LMAN_SYM_OUTLINE -150,125,150,-125
J 0
(-6375 5800);
DISPLAY 0.468085 (-6375 5800);
PAINT GREEN (-6375 5800);
DISPLAY INVISIBLE (-6375 5800);
FORCEPROP 1 LAST PATH I1
J 0
(-6375 5800);
DISPLAY 0.723404 (-6375 5800);
PAINT GREEN (-6375 5800);
DISPLAY INVISIBLE (-6375 5800);
FORCEPROP 1 LAST PART_NUMBER AL2G0066C00
J 0
(-6529 5978);
DISPLAY 0.489362 (-6529 5978);
PAINT SKYBLUE (-6529 5978);
DISPLAY INVISIBLE (-6529 5978);
FORCEADD Q_RES..2
R 2
(-8200 5325);
FORCEPROP 1 LAST LOCATION R1646
J 2
(-8250 5475);
DISPLAY 0.489362 (-8250 5475);
PAINT SKYBLUE (-8250 5475);
FORCEPROP 0 LAST $SEC 1
J 0
(-8250 5525);
DISPLAY 0.680851 (-8250 5525);
PAINT MONO (-8250 5525);
DISPLAY INVISIBLE (-8250 5525);
FORCEPROP 0 LAST CDS_SEC 1
J 0
(-8250 5525);
DISPLAY 1.021277 (-8250 5525);
DISPLAY INVISIBLE (-8250 5525);
FORCEPROP 1 LASTPIN (-8200 5425) $PN 1
J 2
(-8205 5387);
DISPLAY 0.489362 (-8205 5387);
PAINT MONO (-8205 5387);
FORCEPROP 1 LASTPIN (-8200 5225) $PN 2
J 2
(-8205 5235);
DISPLAY 0.489362 (-8205 5235);
PAINT MONO (-8205 5235);
FORCEPROP 1 LAST WATTAGE 1/16W
J 2
(-8250 5325);
DISPLAY 0.489362 (-8250 5325);
PAINT SKYBLUE (-8250 5325);
FORCEPROP 1 LAST MATERIAL CHIP
J 2
(-8250 5275);
DISPLAY 0.489362 (-8250 5275);
PAINT SKYBLUE (-8250 5275);
FORCEPROP 1 LAST TOLERANCE 1%
J 2
(-8250 5375);
DISPLAY 0.489362 (-8250 5375);
PAINT SKYBLUE (-8250 5375);
FORCEPROP 1 LAST VALUE 1K
J 2
(-8250 5425);
DISPLAY 0.489362 (-8250 5425);
PAINT SKYBLUE (-8250 5425);
FORCEPROP 1 LAST PACK_TYPE 0402LF
J 2
(-8250 5225);
DISPLAY 0.489362 (-8250 5225);
PAINT SKYBLUE (-8250 5225);
FORCEPROP 2 LAST CDS_LIB pure_quanta
J 2
(-8200 5325);
DISPLAY INVISIBLE (-8200 5325);
FORCEPROP 1 LAST PATH I10
J 2
(-8250 5500);
DISPLAY 0.978723 (-8250 5500);
PAINT WHITE (-8250 5500);
DISPLAY INVISIBLE (-8250 5500);
FORCEPROP 1 LAST PART_NUMBER CS21002FB06
J 2
(-8250 5175);
DISPLAY 0.489362 (-8250 5175);
PAINT SKYBLUE (-8250 5175);
DISPLAY INVISIBLE (-8250 5175);
FORCEADD Q_RES..2
(-7600 5500);
FORCEPROP 1 LAST LOCATION R1647
J 0
(-7550 5650);
DISPLAY 0.489362 (-7550 5650);
PAINT SKYBLUE (-7550 5650);
FORCEPROP 0 LAST $SEC 1
J 0
(-7550 5700);
DISPLAY 0.680851 (-7550 5700);
PAINT MONO (-7550 5700);
DISPLAY INVISIBLE (-7550 5700);
FORCEPROP 0 LAST CDS_SEC 1
J 0
(-7550 5700);
DISPLAY 1.021277 (-7550 5700);
DISPLAY INVISIBLE (-7550 5700);
FORCEPROP 1 LASTPIN (-7600 5600) $PN 1
J 0
(-7595 5562);
DISPLAY 0.489362 (-7595 5562);
PAINT MONO (-7595 5562);
FORCEPROP 1 LASTPIN (-7600 5400) $PN 2
J 0
(-7595 5410);
DISPLAY 0.489362 (-7595 5410);
PAINT MONO (-7595 5410);
FORCEPROP 1 LAST WATTAGE 1/16W
J 0
(-7550 5500);
DISPLAY 0.489362 (-7550 5500);
PAINT SKYBLUE (-7550 5500);
FORCEPROP 1 LAST VALUE 1K
J 0
(-7550 5600);
DISPLAY 0.489362 (-7550 5600);
PAINT SKYBLUE (-7550 5600);
FORCEPROP 1 LAST TOLERANCE 1%
J 0
(-7550 5550);
DISPLAY 0.489362 (-7550 5550);
PAINT SKYBLUE (-7550 5550);
FORCEPROP 1 LAST MATERIAL CHIP
J 0
(-7550 5450);
DISPLAY 0.489362 (-7550 5450);
PAINT SKYBLUE (-7550 5450);
FORCEPROP 1 LAST PACK_TYPE 0402LF
J 0
(-7550 5400);
DISPLAY 0.489362 (-7550 5400);
PAINT SKYBLUE (-7550 5400);
FORCEPROP 2 LAST CDS_LIB pure_quanta
J 2
(-7600 5500);
DISPLAY INVISIBLE (-7600 5500);
FORCEPROP 1 LAST PATH I11
J 0
(-7550 5675);
DISPLAY 0.978723 (-7550 5675);
PAINT WHITE (-7550 5675);
DISPLAY INVISIBLE (-7550 5675);
FORCEPROP 1 LAST PART_NUMBER CS21002FB06
J 0
(-7550 5350);
DISPLAY 0.489362 (-7550 5350);
PAINT SKYBLUE (-7550 5350);
DISPLAY INVISIBLE (-7550 5350);
FORCEADD UNIVERSAL_POWER..1
(-7600 5700);
FORCEPROP 3 LASTPIN (-7600 5650) SIG_NAME PVDD18_S5_P0\g
J 0
(-7590 5660);
DISPLAY 0.659574 (-7590 5660);
PAINT MONO (-7590 5660);
DISPLAY INVISIBLE (-7590 5660);
FORCEPROP 1 LAST HDL_POWER PVDD18_S5_P0
J 1
(-7600 5750);
DISPLAY 0.489362 (-7600 5750);
PAINT GREEN (-7600 5750);
FORCEPROP 2 LAST CDS_LIB pure_quanta_power
J 0
(-7600 5700);
DISPLAY INVISIBLE (-7600 5700);
FORCEPROP 1 LAST PATH I12
J 0
(-7550 5725);
DISPLAY 0.872340 (-7550 5725);
PAINT AQUA (-7550 5725);
DISPLAY INVISIBLE (-7550 5725);
FORCEADD GND..1
(-5975 5600);
FORCEPROP 3 LASTPIN (-5975 5650) SIG_NAME GND\g
J 0
(-5965 5660);
DISPLAY 0.659574 (-5965 5660);
PAINT MONO (-5965 5660);
DISPLAY INVISIBLE (-5965 5660);
FORCEPROP 1 LAST SIZE 1B
J 0
(-5900 5550);
DISPLAY 0.872340 (-5900 5550);
PAINT GREEN (-5900 5550);
DISPLAY INVISIBLE (-5900 5550);
FORCEPROP 2 LAST CDS_LIB pure_quanta_power
J 0
(-5975 5600);
DISPLAY INVISIBLE (-5975 5600);
FORCEPROP 1 LAST HDL_POWER GND
J 0
(-5975 5750);
DISPLAY 0.872340 (-5975 5750);
PAINT GREEN (-5975 5750);
DISPLAY INVISIBLE (-5975 5750);
FORCEPROP 1 LAST PATH I13
J 0
(-5900 5600);
DISPLAY 0.872340 (-5900 5600);
PAINT AQUA (-5900 5600);
DISPLAY INVISIBLE (-5900 5600);
FORCEADD GND..1
(-5725 5925);
FORCEPROP 3 LASTPIN (-5725 5975) SIG_NAME GND\g
J 0
(-5715 5985);
DISPLAY 0.659574 (-5715 5985);
PAINT MONO (-5715 5985);
DISPLAY INVISIBLE (-5715 5985);
FORCEPROP 1 LAST SIZE 1B
J 0
(-5650 5875);
DISPLAY 0.872340 (-5650 5875);
PAINT GREEN (-5650 5875);
DISPLAY INVISIBLE (-5650 5875);
FORCEPROP 2 LAST CDS_LIB pure_quanta_power
J 0
(-5725 5925);
DISPLAY INVISIBLE (-5725 5925);
FORCEPROP 1 LAST HDL_POWER GND
J 0
(-5725 6075);
DISPLAY 0.872340 (-5725 6075);
PAINT GREEN (-5725 6075);
DISPLAY INVISIBLE (-5725 6075);
FORCEPROP 1 LAST PATH I14
J 0
(-5650 5925);
DISPLAY 0.872340 (-5650 5925);
PAINT AQUA (-5650 5925);
DISPLAY INVISIBLE (-5650 5925);
FORCEADD Q_CAP..1
(-5725 6125);
FORCEPROP 1 LAST LOCATION C1519
J 0
(-5625 6275);
DISPLAY 0.489362 (-5625 6275);
PAINT SKYBLUE (-5625 6275);
FORCEPROP 2 LAST $SEC 1
J 0
(-5675 6325);
PAINT MONO (-5675 6325);
DISPLAY INVISIBLE (-5675 6325);
FORCEPROP 2 LAST CDS_SEC 1
J 0
(-5675 6325);
PAINT MONO (-5675 6325);
DISPLAY INVISIBLE (-5675 6325);
FORCEPROP 1 LASTPIN (-5725 6225) $PN 1
J 0
(-5715 6205);
DISPLAY 0.489362 (-5715 6205);
PAINT GREEN (-5715 6205);
FORCEPROP 1 LASTPIN (-5725 6025) $PN 2
J 0
(-5715 6005);
DISPLAY 0.489362 (-5715 6005);
PAINT GREEN (-5715 6005);
FORCEPROP 1 LAST MATERIAL X7R
J 0
(-5625 6075);
DISPLAY 0.489362 (-5625 6075);
PAINT SKYBLUE (-5625 6075);
FORCEPROP 1 LAST TOLERANCE 10%
J 0
(-5625 6125);
DISPLAY 0.489362 (-5625 6125);
PAINT SKYBLUE (-5625 6125);
FORCEPROP 1 LAST VOLTAGE 16V
J 0
(-5625 6175);
DISPLAY 0.489362 (-5625 6175);
PAINT SKYBLUE (-5625 6175);
FORCEPROP 1 LAST VALUE 0.1UF
J 0
(-5625 6225);
DISPLAY 0.489362 (-5625 6225);
PAINT SKYBLUE (-5625 6225);
FORCEPROP 1 LAST PACK_TYPE C0402
J 0
(-5625 5975);
DISPLAY 0.489362 (-5625 5975);
PAINT SKYBLUE (-5625 5975);
FORCEPROP 2 LAST CDS_LIB pure_quanta
J 0
(-5725 6125);
DISPLAY INVISIBLE (-5725 6125);
FORCEPROP 1 LAST PATH I15
J 0
(-5675 6275);
DISPLAY 0.978723 (-5675 6275);
PAINT WHITE (-5675 6275);
DISPLAY INVISIBLE (-5675 6275);
FORCEPROP 1 LAST PART_NUMBER CH4103K1B08
J 0
(-5625 6025);
DISPLAY 0.489362 (-5625 6025);
PAINT SKYBLUE (-5625 6025);
DISPLAY INVISIBLE (-5625 6025);
FORCEADD UNIVERSAL_POWER..1
(-5950 6400);
FORCEPROP 3 LASTPIN (-5950 6350) SIG_NAME PVDD18_S5_P0\g
J 0
(-5940 6360);
DISPLAY 0.659574 (-5940 6360);
PAINT MONO (-5940 6360);
DISPLAY INVISIBLE (-5940 6360);
FORCEPROP 1 LAST HDL_POWER PVDD18_S5_P0
J 1
(-5950 6450);
DISPLAY 0.489362 (-5950 6450);
PAINT GREEN (-5950 6450);
FORCEPROP 2 LAST CDS_LIB pure_quanta_power
J 0
(-5950 6400);
PAINT MONO (-5950 6400);
DISPLAY INVISIBLE (-5950 6400);
FORCEPROP 1 LAST PATH I16
J 0
(-5900 6425);
DISPLAY 0.872340 (-5900 6425);
PAINT AQUA (-5900 6425);
DISPLAY INVISIBLE (-5900 6425);
FORCEADD SN74AUC2G66DCTR..1
(-4975 4450);
FORCEPROP 1 LAST LOCATION U13
J 0
(-5129 4682);
DISPLAY 0.489362 (-5129 4682);
PAINT SKYBLUE (-5129 4682);
FORCEPROP 2 LAST SEC 1
J 0
(-5125 4825);
DISPLAY 0.680851 (-5125 4825);
PAINT MONO (-5125 4825);
DISPLAY INVISIBLE (-5125 4825);
FORCEPROP 2 LASTPIN (-5275 4525) $PN 1
J 2
(-5285 4535);
DISPLAY 0.489362 (-5285 4535);
PAINT MONO (-5285 4535);
FORCEPROP 2 LASTPIN (-4675 4475) $PN 2
J 0
(-4665 4485);
DISPLAY 0.489362 (-4665 4485);
PAINT MONO (-4665 4485);
FORCEPROP 2 LASTPIN (-5275 4475) $PN 7
J 2
(-5285 4485);
DISPLAY 0.489362 (-5285 4485);
PAINT MONO (-5285 4485);
FORCEPROP 2 LASTPIN (-5275 4425) $PN 5
J 2
(-5285 4435);
DISPLAY 0.489362 (-5285 4435);
PAINT MONO (-5285 4435);
FORCEPROP 2 LASTPIN (-4675 4425) $PN 6
J 0
(-4665 4435);
DISPLAY 0.489362 (-4665 4435);
PAINT MONO (-4665 4435);
FORCEPROP 2 LASTPIN (-5275 4375) $PN 3
J 2
(-5285 4385);
DISPLAY 0.489362 (-5285 4385);
PAINT MONO (-5285 4385);
FORCEPROP 2 LASTPIN (-4675 4375) $PN 4
J 0
(-4665 4385);
DISPLAY 0.489362 (-4665 4385);
PAINT MONO (-4665 4385);
FORCEPROP 2 LASTPIN (-4675 4525) $PN 8
J 0
(-4665 4535);
DISPLAY 0.489362 (-4665 4535);
PAINT MONO (-4665 4535);
FORCEPROP 1 LAST MATERIAL IC
J 0
(-5129 4579);
DISPLAY 0.489362 (-5129 4579);
PAINT SKYBLUE (-5129 4579);
FORCEPROP 2 LAST VALUE SN74AUC2G66DCTR
J 0
(-5125 4725);
DISPLAY 0.489362 (-5125 4725);
PAINT SKYBLUE (-5125 4725);
FORCEPROP 2 LAST PART_TYPE SMLF
J 0
(-5125 4775);
DISPLAY 1.021277 (-5125 4775);
FORCEPROP 2 LAST CDS_LIB pure_quanta
J 0
(-4975 4450);
DISPLAY INVISIBLE (-4975 4450);
FORCEPROP 1 LAST CDS_LMAN_SYM_OUTLINE -150,125,150,-125
J 0
(-4975 4450);
DISPLAY 0.468085 (-4975 4450);
PAINT GREEN (-4975 4450);
DISPLAY INVISIBLE (-4975 4450);
FORCEPROP 1 LAST NEEDS_NO_SIZE TRUE
J 0
(-4975 4450);
DISPLAY 0.723404 (-4975 4450);
PAINT GREEN (-4975 4450);
DISPLAY INVISIBLE (-4975 4450);
FORCEPROP 2 LAST SEC_TYPE 
J 0
(-5125 4825);
DISPLAY 1.021277 (-5125 4825);
DISPLAY INVISIBLE (-5125 4825);
FORCEPROP 1 LAST PATH I17
J 0
(-4975 4450);
DISPLAY 0.723404 (-4975 4450);
PAINT GREEN (-4975 4450);
DISPLAY INVISIBLE (-4975 4450);
FORCEPROP 1 LAST PART_NUMBER AL2G0066C00
J 0
(-5129 4628);
DISPLAY 0.489362 (-5129 4628);
PAINT SKYBLUE (-5129 4628);
DISPLAY INVISIBLE (-5129 4628);
FORCEADD OFFPAGE..1
(-6425 4525);
FORCEPROP 2 LAST $XR0 27 
J 0
(-6646 4525);
DISPLAY 0.638298 (-6646 4525);
PAINT MONO (-6646 4525);
FORCEPROP 2 LAST CDS_LIB standard
J 0
(-6425 4525);
DISPLAY INVISIBLE (-6425 4525);
FORCEPROP 1 LAST OFFPAGE TRUE
J 0
(-6100 4400);
DISPLAY 0.872340 (-6100 4400);
PAINT GREEN (-6100 4400);
DISPLAY INVISIBLE (-6100 4400);
FORCEPROP 1 LAST COMMENT_BODY TRUE
J 0
(-6300 4425);
DISPLAY 0.872340 (-6300 4425);
PAINT GREEN (-6300 4425);
DISPLAY INVISIBLE (-6300 4425);
FORCEPROP 2 LAST PATH I18
J 0
(-6675 4575);
DISPLAY 1.021277 (-6675 4575);
DISPLAY INVISIBLE (-6675 4575);
FORCEADD GND..1
(-7600 4650);
FORCEPROP 3 LASTPIN (-7600 4700) SIG_NAME GND\g
J 0
(-7590 4710);
DISPLAY 0.659574 (-7590 4710);
PAINT MONO (-7590 4710);
DISPLAY INVISIBLE (-7590 4710);
FORCEPROP 1 LAST SIZE 1B
J 0
(-7525 4600);
DISPLAY 0.872340 (-7525 4600);
PAINT GREEN (-7525 4600);
DISPLAY INVISIBLE (-7525 4600);
FORCEPROP 2 LAST CDS_LIB pure_quanta_power
J 0
(-7600 4650);
DISPLAY INVISIBLE (-7600 4650);
FORCEPROP 1 LAST HDL_POWER GND
J 0
(-7600 4800);
DISPLAY 0.872340 (-7600 4800);
PAINT GREEN (-7600 4800);
DISPLAY INVISIBLE (-7600 4800);
FORCEPROP 1 LAST PATH I19
J 0
(-7525 4650);
DISPLAY 0.872340 (-7525 4650);
PAINT AQUA (-7525 4650);
DISPLAY INVISIBLE (-7525 4650);
FORCEADD Q_RES..1
(-5225 5825);
FORCEPROP 1 LAST LOCATION R1648
J 0
(-5100 5825);
DISPLAY 0.489362 (-5100 5825);
PAINT SKYBLUE (-5100 5825);
FORCEPROP 0 LAST $SEC 1
J 0
(-5125 5875);
DISPLAY 0.680851 (-5125 5875);
PAINT MONO (-5125 5875);
DISPLAY INVISIBLE (-5125 5875);
FORCEPROP 0 LAST CDS_SEC 1
J 0
(-5125 5875);
DISPLAY 1.021277 (-5125 5875);
DISPLAY INVISIBLE (-5125 5875);
FORCEPROP 1 LASTPIN (-5325 5825) $PN 1
J 0
(-5313 5837);
DISPLAY 0.489362 (-5313 5837);
PAINT MONO (-5313 5837);
FORCEPROP 1 LASTPIN (-5125 5825) $PN 2
J 0
(-5163 5837);
DISPLAY 0.489362 (-5163 5837);
PAINT MONO (-5163 5837);
FORCEPROP 1 LAST VALUE 0
J 2
(-5325 5825);
DISPLAY 0.489362 (-5325 5825);
PAINT SKYBLUE (-5325 5825);
FORCEPROP 1 LAST TOLERANCE 5%
J 0
(-5125 5800);
DISPLAY 0.489362 (-5125 5800);
PAINT SKYBLUE (-5125 5800);
FORCEPROP 1 LAST MATERIAL CHIP
J 0
(-5400 5800);
DISPLAY 0.489362 (-5400 5800);
PAINT SKYBLUE (-5400 5800);
FORCEPROP 2 LAST CDS_LIB pure_quanta
J 0
(-5225 5825);
DISPLAY INVISIBLE (-5225 5825);
FORCEPROP 1 LAST WATTAGE 1/16W
J 2
(-5250 5675);
DISPLAY 0.978723 (-5250 5675);
PAINT SKYBLUE (-5250 5675);
DISPLAY INVISIBLE (-5250 5675);
FORCEPROP 1 LAST PACK_TYPE 0402LF
J 0
(-4975 5675);
DISPLAY 0.978723 (-4975 5675);
PAINT SKYBLUE (-4975 5675);
DISPLAY INVISIBLE (-4975 5675);
FORCEPROP 1 LAST PATH I2
J 0
(-5275 5975);
DISPLAY 0.978723 (-5275 5975);
PAINT WHITE (-5275 5975);
DISPLAY INVISIBLE (-5275 5975);
FORCEPROP 1 LAST PART_NUMBER CS00002JB13
J 0
(-5275 5925);
DISPLAY 0.978723 (-5275 5925);
PAINT SKYBLUE (-5275 5925);
DISPLAY INVISIBLE (-5275 5925);
FORCEADD UNIVERSAL_POWER..1
(-4225 5050);
FORCEPROP 3 LASTPIN (-4225 5000) SIG_NAME PVDD18_S5_P0\g
J 0
(-4215 5010);
DISPLAY 0.659574 (-4215 5010);
PAINT MONO (-4215 5010);
DISPLAY INVISIBLE (-4215 5010);
FORCEPROP 1 LAST HDL_POWER PVDD18_S5_P0
J 1
(-4225 5100);
DISPLAY 0.489362 (-4225 5100);
PAINT GREEN (-4225 5100);
FORCEPROP 2 LAST CDS_LIB pure_quanta_power
J 0
(-4225 5050);
PAINT MONO (-4225 5050);
DISPLAY INVISIBLE (-4225 5050);
FORCEPROP 1 LAST PATH I20
J 0
(-4175 5075);
DISPLAY 0.872340 (-4175 5075);
PAINT AQUA (-4175 5075);
DISPLAY INVISIBLE (-4175 5075);
FORCEADD GND..1
(-4000 4575);
FORCEPROP 3 LASTPIN (-4000 4625) SIG_NAME GND\g
J 0
(-3990 4635);
DISPLAY 0.659574 (-3990 4635);
PAINT MONO (-3990 4635);
DISPLAY INVISIBLE (-3990 4635);
FORCEPROP 1 LAST SIZE 1B
J 0
(-3925 4525);
DISPLAY 0.872340 (-3925 4525);
PAINT GREEN (-3925 4525);
DISPLAY INVISIBLE (-3925 4525);
FORCEPROP 2 LAST CDS_LIB pure_quanta_power
J 0
(-4000 4575);
DISPLAY INVISIBLE (-4000 4575);
FORCEPROP 1 LAST HDL_POWER GND
J 0
(-4000 4725);
DISPLAY 0.872340 (-4000 4725);
PAINT GREEN (-4000 4725);
DISPLAY INVISIBLE (-4000 4725);
FORCEPROP 1 LAST PATH I21
J 0
(-3925 4575);
DISPLAY 0.872340 (-3925 4575);
PAINT AQUA (-3925 4575);
DISPLAY INVISIBLE (-3925 4575);
FORCEADD Q_CAP..1
(-4000 4775);
FORCEPROP 1 LAST LOCATION C1521
J 0
(-3900 4925);
DISPLAY 0.489362 (-3900 4925);
PAINT SKYBLUE (-3900 4925);
FORCEPROP 2 LAST $SEC 1
J 0
(-3950 4975);
PAINT MONO (-3950 4975);
DISPLAY INVISIBLE (-3950 4975);
FORCEPROP 2 LAST CDS_SEC 1
J 0
(-3950 4975);
PAINT MONO (-3950 4975);
DISPLAY INVISIBLE (-3950 4975);
FORCEPROP 1 LASTPIN (-4000 4875) $PN 1
J 0
(-3990 4855);
DISPLAY 0.489362 (-3990 4855);
PAINT GREEN (-3990 4855);
FORCEPROP 1 LASTPIN (-4000 4675) $PN 2
J 0
(-3990 4655);
DISPLAY 0.489362 (-3990 4655);
PAINT GREEN (-3990 4655);
FORCEPROP 1 LAST TOLERANCE 10%
J 0
(-3900 4775);
DISPLAY 0.489362 (-3900 4775);
PAINT SKYBLUE (-3900 4775);
FORCEPROP 1 LAST MATERIAL X7R
J 0
(-3900 4725);
DISPLAY 0.489362 (-3900 4725);
PAINT SKYBLUE (-3900 4725);
FORCEPROP 1 LAST VOLTAGE 16V
J 0
(-3900 4825);
DISPLAY 0.489362 (-3900 4825);
PAINT SKYBLUE (-3900 4825);
FORCEPROP 1 LAST VALUE 0.1UF
J 0
(-3900 4875);
DISPLAY 0.489362 (-3900 4875);
PAINT SKYBLUE (-3900 4875);
FORCEPROP 1 LAST PACK_TYPE C0402
J 0
(-3900 4625);
DISPLAY 0.489362 (-3900 4625);
PAINT SKYBLUE (-3900 4625);
FORCEPROP 2 LAST CDS_LIB pure_quanta
J 0
(-4000 4775);
DISPLAY INVISIBLE (-4000 4775);
FORCEPROP 1 LAST PATH I22
J 0
(-3950 4925);
DISPLAY 0.978723 (-3950 4925);
PAINT WHITE (-3950 4925);
DISPLAY INVISIBLE (-3950 4925);
FORCEPROP 1 LAST PART_NUMBER CH4103K1B08
J 0
(-3900 4675);
DISPLAY 0.489362 (-3900 4675);
PAINT SKYBLUE (-3900 4675);
DISPLAY INVISIBLE (-3900 4675);
FORCEADD SN74AUC2G66DCTR..1
(-3125 4400);
FORCEPROP 1 LAST LOCATION U14
J 0
(-3279 4632);
DISPLAY 0.489362 (-3279 4632);
PAINT SKYBLUE (-3279 4632);
FORCEPROP 2 LAST SEC 1
J 0
(-3275 4775);
DISPLAY 0.680851 (-3275 4775);
PAINT MONO (-3275 4775);
DISPLAY INVISIBLE (-3275 4775);
FORCEPROP 2 LASTPIN (-3425 4475) $PN 1
J 2
(-3435 4485);
DISPLAY 0.489362 (-3435 4485);
PAINT MONO (-3435 4485);
FORCEPROP 2 LASTPIN (-2825 4425) $PN 2
J 0
(-2815 4435);
DISPLAY 0.489362 (-2815 4435);
PAINT MONO (-2815 4435);
FORCEPROP 2 LASTPIN (-3425 4425) $PN 7
J 2
(-3435 4435);
DISPLAY 0.489362 (-3435 4435);
PAINT MONO (-3435 4435);
FORCEPROP 2 LASTPIN (-3425 4375) $PN 5
J 2
(-3435 4385);
DISPLAY 0.489362 (-3435 4385);
PAINT MONO (-3435 4385);
FORCEPROP 2 LASTPIN (-2825 4375) $PN 6
J 0
(-2815 4385);
DISPLAY 0.489362 (-2815 4385);
PAINT MONO (-2815 4385);
FORCEPROP 2 LASTPIN (-3425 4325) $PN 3
J 2
(-3435 4335);
DISPLAY 0.489362 (-3435 4335);
PAINT MONO (-3435 4335);
FORCEPROP 2 LASTPIN (-2825 4325) $PN 4
J 0
(-2815 4335);
DISPLAY 0.489362 (-2815 4335);
PAINT MONO (-2815 4335);
FORCEPROP 2 LASTPIN (-2825 4475) $PN 8
J 0
(-2815 4485);
DISPLAY 0.489362 (-2815 4485);
PAINT MONO (-2815 4485);
FORCEPROP 2 LAST VALUE SN74AUC2G66DCTR
J 0
(-3275 4675);
DISPLAY 0.489362 (-3275 4675);
PAINT SKYBLUE (-3275 4675);
FORCEPROP 1 LAST MATERIAL IC
J 0
(-3279 4529);
DISPLAY 0.489362 (-3279 4529);
PAINT SKYBLUE (-3279 4529);
FORCEPROP 2 LAST PART_TYPE SMLF
J 0
(-3275 4725);
DISPLAY 1.021277 (-3275 4725);
FORCEPROP 2 LAST CDS_LIB pure_quanta
J 0
(-3125 4400);
DISPLAY INVISIBLE (-3125 4400);
FORCEPROP 1 LAST NEEDS_NO_SIZE TRUE
J 0
(-3125 4400);
DISPLAY 0.723404 (-3125 4400);
PAINT GREEN (-3125 4400);
DISPLAY INVISIBLE (-3125 4400);
FORCEPROP 1 LAST CDS_LMAN_SYM_OUTLINE -150,125,150,-125
J 0
(-3125 4400);
DISPLAY 0.468085 (-3125 4400);
PAINT GREEN (-3125 4400);
DISPLAY INVISIBLE (-3125 4400);
FORCEPROP 2 LAST SEC_TYPE 
J 0
(-3275 4775);
DISPLAY 1.021277 (-3275 4775);
DISPLAY INVISIBLE (-3275 4775);
FORCEPROP 1 LAST PATH I23
J 0
(-3125 4400);
DISPLAY 0.723404 (-3125 4400);
PAINT GREEN (-3125 4400);
DISPLAY INVISIBLE (-3125 4400);
FORCEPROP 1 LAST PART_NUMBER AL2G0066C00
J 0
(-3279 4578);
DISPLAY 0.489362 (-3279 4578);
PAINT SKYBLUE (-3279 4578);
DISPLAY INVISIBLE (-3279 4578);
FORCEADD Q_RES..2
R 2
(-5225 3400);
FORCEPROP 1 LAST LOCATION R1649
J 2
(-5275 3550);
DISPLAY 0.489362 (-5275 3550);
PAINT SKYBLUE (-5275 3550);
FORCEPROP 0 LAST $SEC 1
J 0
(-5275 3600);
DISPLAY 0.680851 (-5275 3600);
PAINT MONO (-5275 3600);
DISPLAY INVISIBLE (-5275 3600);
FORCEPROP 0 LAST CDS_SEC 1
J 0
(-5275 3600);
DISPLAY 1.021277 (-5275 3600);
DISPLAY INVISIBLE (-5275 3600);
FORCEPROP 1 LASTPIN (-5225 3500) $PN 1
J 2
(-5230 3462);
DISPLAY 0.489362 (-5230 3462);
PAINT MONO (-5230 3462);
FORCEPROP 1 LASTPIN (-5225 3300) $PN 2
J 2
(-5230 3310);
DISPLAY 0.489362 (-5230 3310);
PAINT MONO (-5230 3310);
FORCEPROP 1 LAST WATTAGE 1/16W
J 2
(-5275 3400);
DISPLAY 0.489362 (-5275 3400);
PAINT SKYBLUE (-5275 3400);
FORCEPROP 1 LAST MATERIAL CHIP
J 2
(-5275 3350);
DISPLAY 0.489362 (-5275 3350);
PAINT SKYBLUE (-5275 3350);
FORCEPROP 1 LAST TOLERANCE 1%
J 2
(-5275 3450);
DISPLAY 0.489362 (-5275 3450);
PAINT SKYBLUE (-5275 3450);
FORCEPROP 1 LAST VALUE 1K
J 2
(-5275 3500);
DISPLAY 0.489362 (-5275 3500);
PAINT SKYBLUE (-5275 3500);
FORCEPROP 1 LAST PACK_TYPE 0402LF
J 2
(-5275 3300);
DISPLAY 0.489362 (-5275 3300);
PAINT SKYBLUE (-5275 3300);
FORCEPROP 2 LAST CDS_LIB pure_quanta
J 2
(-5225 3400);
DISPLAY INVISIBLE (-5225 3400);
FORCEPROP 1 LAST PATH I25
J 2
(-5275 3575);
DISPLAY 0.978723 (-5275 3575);
PAINT WHITE (-5275 3575);
DISPLAY INVISIBLE (-5275 3575);
FORCEPROP 1 LAST PART_NUMBER CS21002FB06
J 2
(-5275 3250);
DISPLAY 0.489362 (-5275 3250);
PAINT SKYBLUE (-5275 3250);
DISPLAY INVISIBLE (-5275 3250);
FORCEADD UNIVERSAL_POWER..1
(-4550 3725);
FORCEPROP 3 LASTPIN (-4550 3675) SIG_NAME PVDD18_S5_P0\g
J 0
(-4540 3685);
DISPLAY 0.659574 (-4540 3685);
PAINT MONO (-4540 3685);
DISPLAY INVISIBLE (-4540 3685);
FORCEPROP 1 LAST HDL_POWER PVDD18_S5_P0
J 1
(-4550 3775);
DISPLAY 0.489362 (-4550 3775);
PAINT GREEN (-4550 3775);
FORCEPROP 2 LAST CDS_LIB pure_quanta_power
J 0
(-4550 3725);
DISPLAY INVISIBLE (-4550 3725);
FORCEPROP 1 LAST PATH I26
J 0
(-4500 3750);
DISPLAY 0.872340 (-4500 3750);
PAINT AQUA (-4500 3750);
DISPLAY INVISIBLE (-4500 3750);
FORCEADD Q_RES..2
(-4550 3525);
FORCEPROP 1 LAST LOCATION R1650
J 0
(-4500 3675);
DISPLAY 0.489362 (-4500 3675);
PAINT SKYBLUE (-4500 3675);
FORCEPROP 0 LAST $SEC 1
J 0
(-4500 3725);
DISPLAY 0.680851 (-4500 3725);
PAINT MONO (-4500 3725);
DISPLAY INVISIBLE (-4500 3725);
FORCEPROP 0 LAST CDS_SEC 1
J 0
(-4500 3725);
DISPLAY 1.021277 (-4500 3725);
DISPLAY INVISIBLE (-4500 3725);
FORCEPROP 1 LASTPIN (-4550 3625) $PN 1
J 0
(-4545 3587);
DISPLAY 0.489362 (-4545 3587);
PAINT MONO (-4545 3587);
FORCEPROP 1 LASTPIN (-4550 3425) $PN 2
J 0
(-4545 3435);
DISPLAY 0.489362 (-4545 3435);
PAINT MONO (-4545 3435);
FORCEPROP 1 LAST WATTAGE 1/16W
J 0
(-4500 3525);
DISPLAY 0.489362 (-4500 3525);
PAINT SKYBLUE (-4500 3525);
FORCEPROP 1 LAST MATERIAL CHIP
J 0
(-4500 3475);
DISPLAY 0.489362 (-4500 3475);
PAINT SKYBLUE (-4500 3475);
FORCEPROP 1 LAST TOLERANCE 1%
J 0
(-4500 3575);
DISPLAY 0.489362 (-4500 3575);
PAINT SKYBLUE (-4500 3575);
FORCEPROP 1 LAST VALUE 1K
J 0
(-4500 3625);
DISPLAY 0.489362 (-4500 3625);
PAINT SKYBLUE (-4500 3625);
FORCEPROP 1 LAST PACK_TYPE 0402LF
J 0
(-4500 3425);
DISPLAY 0.489362 (-4500 3425);
PAINT SKYBLUE (-4500 3425);
FORCEPROP 2 LAST CDS_LIB pure_quanta
J 2
(-4550 3525);
DISPLAY INVISIBLE (-4550 3525);
FORCEPROP 1 LAST PATH I27
J 0
(-4500 3700);
DISPLAY 0.978723 (-4500 3700);
PAINT WHITE (-4500 3700);
DISPLAY INVISIBLE (-4500 3700);
FORCEPROP 1 LAST PART_NUMBER CS21002FB06
J 0
(-4500 3375);
DISPLAY 0.489362 (-4500 3375);
PAINT SKYBLUE (-4500 3375);
DISPLAY INVISIBLE (-4500 3375);
FORCEADD UNIVERSAL_POWER..1
(-5225 3650);
FORCEPROP 3 LASTPIN (-5225 3600) SIG_NAME PVDD18_S5_P0\g
J 0
(-5215 3610);
DISPLAY 0.659574 (-5215 3610);
PAINT MONO (-5215 3610);
DISPLAY INVISIBLE (-5215 3610);
FORCEPROP 1 LAST HDL_POWER PVDD18_S5_P0
J 1
(-5225 3700);
DISPLAY 0.489362 (-5225 3700);
PAINT GREEN (-5225 3700);
FORCEPROP 2 LAST CDS_LIB pure_quanta_power
J 0
(-5225 3650);
PAINT MONO (-5225 3650);
DISPLAY INVISIBLE (-5225 3650);
FORCEPROP 1 LAST PATH I28
J 0
(-5175 3675);
DISPLAY 0.872340 (-5175 3675);
PAINT AQUA (-5175 3675);
DISPLAY INVISIBLE (-5175 3675);
FORCEADD GND..1
(-4550 2725);
FORCEPROP 3 LASTPIN (-4550 2775) SIG_NAME GND\g
J 0
(-4540 2785);
DISPLAY 0.659574 (-4540 2785);
PAINT MONO (-4540 2785);
DISPLAY INVISIBLE (-4540 2785);
FORCEPROP 1 LAST SIZE 1B
J 0
(-4475 2675);
DISPLAY 0.872340 (-4475 2675);
PAINT GREEN (-4475 2675);
DISPLAY INVISIBLE (-4475 2675);
FORCEPROP 2 LAST CDS_LIB pure_quanta_power
J 0
(-4550 2725);
DISPLAY INVISIBLE (-4550 2725);
FORCEPROP 1 LAST HDL_POWER GND
J 0
(-4550 2875);
DISPLAY 0.872340 (-4550 2875);
PAINT GREEN (-4550 2875);
DISPLAY INVISIBLE (-4550 2875);
FORCEPROP 1 LAST PATH I29
J 0
(-4475 2725);
DISPLAY 0.872340 (-4475 2725);
PAINT AQUA (-4475 2725);
DISPLAY INVISIBLE (-4475 2725);
FORCEADD GND..1
(-4900 5325);
FORCEPROP 3 LASTPIN (-4900 5375) SIG_NAME GND\g
J 0
(-4890 5385);
DISPLAY 0.659574 (-4890 5385);
PAINT MONO (-4890 5385);
DISPLAY INVISIBLE (-4890 5385);
FORCEPROP 2 LAST CDS_LIB pure_quanta_power
J 0
(-4900 5325);
DISPLAY INVISIBLE (-4900 5325);
FORCEPROP 1 LAST SIZE 1B
J 0
(-4825 5275);
DISPLAY 0.872340 (-4825 5275);
PAINT GREEN (-4825 5275);
DISPLAY INVISIBLE (-4825 5275);
FORCEPROP 1 LAST HDL_POWER GND
J 0
(-4900 5475);
DISPLAY 0.872340 (-4900 5475);
PAINT GREEN (-4900 5475);
DISPLAY INVISIBLE (-4900 5475);
FORCEPROP 1 LAST PATH I3
J 0
(-4825 5325);
DISPLAY 0.872340 (-4825 5325);
PAINT AQUA (-4825 5325);
DISPLAY INVISIBLE (-4825 5325);
FORCEADD OFFPAGE..1
(-6125 3050);
FORCEPROP 2 LAST $XR0 81 
J 0
(-6376 3050);
DISPLAY 0.638298 (-6376 3050);
PAINT MONO (-6376 3050);
FORCEPROP 2 LAST CDS_LIB standard
J 0
(-6125 3050);
DISPLAY INVISIBLE (-6125 3050);
FORCEPROP 1 LAST OFFPAGE TRUE
J 0
(-5800 2925);
DISPLAY 0.872340 (-5800 2925);
PAINT GREEN (-5800 2925);
DISPLAY INVISIBLE (-5800 2925);
FORCEPROP 1 LAST COMMENT_BODY TRUE
J 0
(-6000 2950);
DISPLAY 0.872340 (-6000 2950);
PAINT GREEN (-6000 2950);
DISPLAY INVISIBLE (-6000 2950);
FORCEPROP 2 LAST PATH I30
J 0
(-6375 3100);
DISPLAY 1.021277 (-6375 3100);
DISPLAY INVISIBLE (-6375 3100);
FORCEADD SN74AUC2G66DCTR..1
(-1850 3400);
FORCEPROP 1 LAST LOCATION U154
J 0
(-2004 3632);
DISPLAY 0.489362 (-2004 3632);
PAINT SKYBLUE (-2004 3632);
FORCEPROP 0 LAST $SEC 1
J 0
(-2000 3775);
DISPLAY 0.680851 (-2000 3775);
PAINT MONO (-2000 3775);
DISPLAY INVISIBLE (-2000 3775);
FORCEPROP 0 LAST CDS_SEC 1
J 0
(-2000 3775);
DISPLAY 1.021277 (-2000 3775);
DISPLAY INVISIBLE (-2000 3775);
FORCEPROP 0 LASTPIN (-2150 3475) $PN 1
J 2
(-2160 3485);
DISPLAY 0.489362 (-2160 3485);
PAINT MONO (-2160 3485);
FORCEPROP 0 LASTPIN (-1550 3425) $PN 2
J 0
(-1540 3435);
DISPLAY 0.489362 (-1540 3435);
PAINT MONO (-1540 3435);
FORCEPROP 0 LASTPIN (-2150 3425) $PN 7
J 2
(-2160 3435);
DISPLAY 0.489362 (-2160 3435);
PAINT MONO (-2160 3435);
FORCEPROP 0 LASTPIN (-2150 3375) $PN 5
J 2
(-2160 3385);
DISPLAY 0.489362 (-2160 3385);
PAINT MONO (-2160 3385);
FORCEPROP 0 LASTPIN (-1550 3375) $PN 6
J 0
(-1540 3385);
DISPLAY 0.489362 (-1540 3385);
PAINT MONO (-1540 3385);
FORCEPROP 0 LASTPIN (-2150 3325) $PN 3
J 2
(-2160 3335);
DISPLAY 0.489362 (-2160 3335);
PAINT MONO (-2160 3335);
FORCEPROP 0 LASTPIN (-1550 3325) $PN 4
J 0
(-1540 3335);
DISPLAY 0.489362 (-1540 3335);
PAINT MONO (-1540 3335);
FORCEPROP 0 LASTPIN (-1550 3475) $PN 8
J 0
(-1540 3485);
DISPLAY 0.489362 (-1540 3485);
PAINT MONO (-1540 3485);
FORCEPROP 2 LAST VALUE SN74AUC2G66DCTR
J 0
(-2000 3675);
DISPLAY 0.489362 (-2000 3675);
PAINT SKYBLUE (-2000 3675);
FORCEPROP 1 LAST MATERIAL IC
J 0
(-2004 3529);
DISPLAY 0.489362 (-2004 3529);
PAINT SKYBLUE (-2004 3529);
FORCEPROP 2 LAST PART_TYPE SMLF
J 0
(-2000 3725);
DISPLAY 1.021277 (-2000 3725);
FORCEPROP 2 LAST CDS_LIB pure_quanta
J 0
(-1850 3400);
DISPLAY INVISIBLE (-1850 3400);
FORCEPROP 1 LAST CDS_LMAN_SYM_OUTLINE -150,125,150,-125
J 0
(-1850 3400);
DISPLAY 0.468085 (-1850 3400);
PAINT GREEN (-1850 3400);
DISPLAY INVISIBLE (-1850 3400);
FORCEPROP 1 LAST NEEDS_NO_SIZE TRUE
J 0
(-1850 3400);
DISPLAY 0.723404 (-1850 3400);
PAINT GREEN (-1850 3400);
DISPLAY INVISIBLE (-1850 3400);
FORCEPROP 1 LAST PATH I31
J 0
(-1850 3400);
DISPLAY 0.723404 (-1850 3400);
PAINT GREEN (-1850 3400);
DISPLAY INVISIBLE (-1850 3400);
FORCEPROP 1 LAST PART_NUMBER AL2G0066C00
J 0
(-2004 3578);
DISPLAY 0.489362 (-2004 3578);
PAINT SKYBLUE (-2004 3578);
DISPLAY INVISIBLE (-2004 3578);
FORCEADD OFFPAGE..1
(-3075 3475);
FORCEPROP 2 LAST $XR0 54 
J 0
(-3326 3475);
DISPLAY 0.638298 (-3326 3475);
PAINT MONO (-3326 3475);
FORCEPROP 2 LAST CDS_LIB standard
J 0
(-3075 3475);
DISPLAY INVISIBLE (-3075 3475);
FORCEPROP 1 LAST OFFPAGE TRUE
J 0
(-2750 3350);
DISPLAY 0.872340 (-2750 3350);
PAINT GREEN (-2750 3350);
DISPLAY INVISIBLE (-2750 3350);
FORCEPROP 1 LAST COMMENT_BODY TRUE
J 0
(-2950 3375);
DISPLAY 0.872340 (-2950 3375);
PAINT GREEN (-2950 3375);
DISPLAY INVISIBLE (-2950 3375);
FORCEPROP 2 LAST PATH I32
J 0
(-3325 3525);
DISPLAY 1.021277 (-3325 3525);
DISPLAY INVISIBLE (-3325 3525);
FORCEADD OFFPAGE..2
(-1000 4425);
FORCEPROP 2 LAST $XR0 54 
J 0
(-811 4425);
DISPLAY 0.638298 (-811 4425);
PAINT MONO (-811 4425);
FORCEPROP 2 LAST CDS_LIB standard
J 0
(-1000 4425);
PAINT MONO (-1000 4425);
DISPLAY INVISIBLE (-1000 4425);
FORCEPROP 1 LAST OFFPAGE TRUE
J 0
(-675 4300);
DISPLAY 0.872340 (-675 4300);
PAINT GREEN (-675 4300);
DISPLAY INVISIBLE (-675 4300);
FORCEPROP 1 LAST COMMENT_BODY TRUE
J 0
(-1045 4330);
DISPLAY 0.872340 (-1045 4330);
PAINT GREEN (-1045 4330);
DISPLAY INVISIBLE (-1045 4330);
FORCEPROP 2 LAST PATH I33
J 0
(-800 4475);
DISPLAY 1.021277 (-800 4475);
DISPLAY INVISIBLE (-800 4475);
FORCEADD Q_RES..1
(-1975 4425);
FORCEPROP 1 LAST LOCATION R1651
J 0
(-1875 4425);
DISPLAY 0.489362 (-1875 4425);
PAINT SKYBLUE (-1875 4425);
FORCEPROP 0 LAST $SEC 1
J 0
(-1875 4475);
DISPLAY 0.680851 (-1875 4475);
PAINT MONO (-1875 4475);
DISPLAY INVISIBLE (-1875 4475);
FORCEPROP 0 LAST CDS_SEC 1
J 0
(-1875 4475);
DISPLAY 1.021277 (-1875 4475);
DISPLAY INVISIBLE (-1875 4475);
FORCEPROP 1 LASTPIN (-2075 4425) $PN 1
J 0
(-2063 4437);
DISPLAY 0.489362 (-2063 4437);
PAINT MONO (-2063 4437);
FORCEPROP 1 LASTPIN (-1875 4425) $PN 2
J 0
(-1913 4437);
DISPLAY 0.489362 (-1913 4437);
PAINT MONO (-1913 4437);
FORCEPROP 1 LAST MATERIAL CHIP
J 0
(-2150 4400);
DISPLAY 0.489362 (-2150 4400);
PAINT SKYBLUE (-2150 4400);
FORCEPROP 1 LAST VALUE 0
J 2
(-2075 4425);
DISPLAY 0.489362 (-2075 4425);
PAINT SKYBLUE (-2075 4425);
FORCEPROP 1 LAST TOLERANCE 5%
J 0
(-1875 4400);
DISPLAY 0.489362 (-1875 4400);
PAINT SKYBLUE (-1875 4400);
FORCEPROP 2 LAST CDS_LIB pure_quanta
J 0
(-1975 4425);
DISPLAY INVISIBLE (-1975 4425);
FORCEPROP 1 LAST WATTAGE 1/16W
J 2
(-2000 4275);
DISPLAY 0.978723 (-2000 4275);
PAINT SKYBLUE (-2000 4275);
DISPLAY INVISIBLE (-2000 4275);
FORCEPROP 1 LAST PACK_TYPE 0402LF
J 0
(-1725 4275);
DISPLAY 0.978723 (-1725 4275);
PAINT SKYBLUE (-1725 4275);
DISPLAY INVISIBLE (-1725 4275);
FORCEPROP 1 LAST PATH I34
J 0
(-2025 4575);
DISPLAY 0.978723 (-2025 4575);
PAINT WHITE (-2025 4575);
DISPLAY INVISIBLE (-2025 4575);
FORCEPROP 1 LAST PART_NUMBER CS00002JB13
J 0
(-2025 4525);
DISPLAY 0.978723 (-2025 4525);
PAINT SKYBLUE (-2025 4525);
DISPLAY INVISIBLE (-2025 4525);
FORCEADD UNIVERSAL_POWER..1
(-2375 5000);
FORCEPROP 3 LASTPIN (-2375 4950) SIG_NAME PVDD18_S5_P0\g
J 0
(-2365 4960);
DISPLAY 0.659574 (-2365 4960);
PAINT MONO (-2365 4960);
DISPLAY INVISIBLE (-2365 4960);
FORCEPROP 1 LAST HDL_POWER PVDD18_S5_P0
J 1
(-2375 5050);
DISPLAY 0.489362 (-2375 5050);
PAINT GREEN (-2375 5050);
FORCEPROP 2 LAST CDS_LIB pure_quanta_power
J 0
(-2375 5000);
PAINT MONO (-2375 5000);
DISPLAY INVISIBLE (-2375 5000);
FORCEPROP 1 LAST PATH I35
J 0
(-2325 5025);
DISPLAY 0.872340 (-2325 5025);
PAINT AQUA (-2325 5025);
DISPLAY INVISIBLE (-2325 5025);
FORCEADD Q_CAP..1
(-2150 4725);
FORCEPROP 1 LAST LOCATION C1522
J 0
(-2050 4875);
DISPLAY 0.489362 (-2050 4875);
PAINT SKYBLUE (-2050 4875);
FORCEPROP 2 LAST $SEC 1
J 0
(-2100 4925);
PAINT MONO (-2100 4925);
DISPLAY INVISIBLE (-2100 4925);
FORCEPROP 2 LAST CDS_SEC 1
J 0
(-2100 4925);
PAINT MONO (-2100 4925);
DISPLAY INVISIBLE (-2100 4925);
FORCEPROP 1 LASTPIN (-2150 4825) $PN 1
J 0
(-2140 4805);
DISPLAY 0.489362 (-2140 4805);
PAINT GREEN (-2140 4805);
FORCEPROP 1 LASTPIN (-2150 4625) $PN 2
J 0
(-2140 4605);
DISPLAY 0.489362 (-2140 4605);
PAINT GREEN (-2140 4605);
FORCEPROP 1 LAST PACK_TYPE C0402
J 0
(-2050 4575);
DISPLAY 0.489362 (-2050 4575);
PAINT SKYBLUE (-2050 4575);
FORCEPROP 1 LAST VOLTAGE 16V
J 0
(-2050 4775);
DISPLAY 0.489362 (-2050 4775);
PAINT SKYBLUE (-2050 4775);
FORCEPROP 1 LAST VALUE 0.1UF
J 0
(-2050 4825);
DISPLAY 0.489362 (-2050 4825);
PAINT SKYBLUE (-2050 4825);
FORCEPROP 1 LAST MATERIAL X7R
J 0
(-2050 4675);
DISPLAY 0.489362 (-2050 4675);
PAINT SKYBLUE (-2050 4675);
FORCEPROP 1 LAST TOLERANCE 10%
J 0
(-2050 4725);
DISPLAY 0.489362 (-2050 4725);
PAINT SKYBLUE (-2050 4725);
FORCEPROP 2 LAST CDS_LIB pure_quanta
J 0
(-2150 4725);
DISPLAY INVISIBLE (-2150 4725);
FORCEPROP 1 LAST PATH I36
J 0
(-2100 4875);
DISPLAY 0.978723 (-2100 4875);
PAINT WHITE (-2100 4875);
DISPLAY INVISIBLE (-2100 4875);
FORCEPROP 1 LAST PART_NUMBER CH4103K1B08
J 0
(-2050 4625);
DISPLAY 0.489362 (-2050 4625);
PAINT SKYBLUE (-2050 4625);
DISPLAY INVISIBLE (-2050 4625);
FORCEADD GND..1
(-2150 4525);
FORCEPROP 3 LASTPIN (-2150 4575) SIG_NAME GND\g
J 0
(-2140 4585);
DISPLAY 0.659574 (-2140 4585);
PAINT MONO (-2140 4585);
DISPLAY INVISIBLE (-2140 4585);
FORCEPROP 2 LAST CDS_LIB pure_quanta_power
J 0
(-2150 4525);
DISPLAY INVISIBLE (-2150 4525);
FORCEPROP 1 LAST SIZE 1B
J 0
(-2075 4475);
DISPLAY 0.872340 (-2075 4475);
PAINT GREEN (-2075 4475);
DISPLAY INVISIBLE (-2075 4475);
FORCEPROP 1 LAST HDL_POWER GND
J 0
(-2150 4675);
DISPLAY 0.872340 (-2150 4675);
PAINT GREEN (-2150 4675);
DISPLAY INVISIBLE (-2150 4675);
FORCEPROP 1 LAST PATH I37
J 0
(-2075 4525);
DISPLAY 0.872340 (-2075 4525);
PAINT AQUA (-2075 4525);
DISPLAY INVISIBLE (-2075 4525);
FORCEADD GND..1
(-4575 4250);
FORCEPROP 3 LASTPIN (-4575 4300) SIG_NAME GND\g
J 0
(-4565 4310);
DISPLAY 0.659574 (-4565 4310);
PAINT MONO (-4565 4310);
DISPLAY INVISIBLE (-4565 4310);
FORCEPROP 1 LAST SIZE 1B
J 0
(-4500 4200);
DISPLAY 0.872340 (-4500 4200);
PAINT GREEN (-4500 4200);
DISPLAY INVISIBLE (-4500 4200);
FORCEPROP 2 LAST CDS_LIB pure_quanta_power
J 0
(-4575 4250);
DISPLAY INVISIBLE (-4575 4250);
FORCEPROP 1 LAST HDL_POWER GND
J 0
(-4575 4400);
DISPLAY 0.872340 (-4575 4400);
PAINT GREEN (-4575 4400);
DISPLAY INVISIBLE (-4575 4400);
FORCEPROP 1 LAST PATH I38
J 0
(-4500 4250);
DISPLAY 0.872340 (-4500 4250);
PAINT AQUA (-4500 4250);
DISPLAY INVISIBLE (-4500 4250);
FORCEADD GND..1
(-2725 4200);
FORCEPROP 3 LASTPIN (-2725 4250) SIG_NAME GND\g
J 0
(-2715 4260);
DISPLAY 0.659574 (-2715 4260);
PAINT MONO (-2715 4260);
DISPLAY INVISIBLE (-2715 4260);
FORCEPROP 1 LAST SIZE 1B
J 0
(-2650 4150);
DISPLAY 0.872340 (-2650 4150);
PAINT GREEN (-2650 4150);
DISPLAY INVISIBLE (-2650 4150);
FORCEPROP 2 LAST CDS_LIB pure_quanta_power
J 0
(-2725 4200);
DISPLAY INVISIBLE (-2725 4200);
FORCEPROP 1 LAST HDL_POWER GND
J 0
(-2725 4350);
DISPLAY 0.872340 (-2725 4350);
PAINT GREEN (-2725 4350);
DISPLAY INVISIBLE (-2725 4350);
FORCEPROP 1 LAST PATH I39
J 0
(-2650 4200);
DISPLAY 0.872340 (-2650 4200);
PAINT AQUA (-2650 4200);
DISPLAY INVISIBLE (-2650 4200);
FORCEADD Q_CAP..1
(-4900 5625);
FORCEPROP 1 LAST LOCATION C1520
J 0
(-4850 5725);
DISPLAY 0.489362 (-4850 5725);
PAINT SKYBLUE (-4850 5725);
FORCEPROP 0 LAST $SEC 1
J 0
(-4850 5775);
PAINT MONO (-4850 5775);
DISPLAY INVISIBLE (-4850 5775);
FORCEPROP 0 LAST CDS_SEC 1
J 0
(-4850 5775);
PAINT MONO (-4850 5775);
DISPLAY INVISIBLE (-4850 5775);
FORCEPROP 1 LASTPIN (-4900 5725) $PN 1
J 0
(-4890 5705);
DISPLAY 0.489362 (-4890 5705);
PAINT GREEN (-4890 5705);
FORCEPROP 1 LASTPIN (-4900 5525) $PN 2
J 0
(-4890 5505);
DISPLAY 0.489362 (-4890 5505);
PAINT GREEN (-4890 5505);
FORCEPROP 1 LAST VALUE 0.01UF
J 0
(-4850 5675);
DISPLAY 0.489362 (-4850 5675);
PAINT SKYBLUE (-4850 5675);
FORCEPROP 1 LAST VOLTAGE 50V
J 0
(-4850 5625);
DISPLAY 0.489362 (-4850 5625);
PAINT SKYBLUE (-4850 5625);
FORCEPROP 1 LAST TOLERANCE 10%
J 0
(-4850 5575);
DISPLAY 0.489362 (-4850 5575);
PAINT SKYBLUE (-4850 5575);
FORCEPROP 1 LAST PACK_TYPE C0402
J 0
(-4850 5475);
DISPLAY 0.489362 (-4850 5475);
PAINT SKYBLUE (-4850 5475);
FORCEPROP 1 LAST MATERIAL EMPTY
J 0
(-4850 5425);
DISPLAY 0.489362 (-4850 5425);
PAINT RED (-4850 5425);
FORCEPROP 2 LAST CDS_LIB pure_quanta
J 0
(-4900 5625);
PAINT MONO (-4900 5625);
DISPLAY INVISIBLE (-4900 5625);
FORCEPROP 1 LAST PATH I4
J 0
(-4850 5775);
DISPLAY 0.978723 (-4850 5775);
PAINT WHITE (-4850 5775);
DISPLAY INVISIBLE (-4850 5775);
FORCEPROP 1 LAST PART_NUMBER CH31006KB18
J 0
(-4850 5525);
DISPLAY 0.489362 (-4850 5525);
PAINT SKYBLUE (-4850 5525);
DISPLAY INVISIBLE (-4850 5525);
FORCEADD GND..1
(-1450 3200);
FORCEPROP 3 LASTPIN (-1450 3250) SIG_NAME GND\g
J 0
(-1440 3260);
DISPLAY 0.659574 (-1440 3260);
PAINT MONO (-1440 3260);
DISPLAY INVISIBLE (-1440 3260);
FORCEPROP 2 LAST CDS_LIB pure_quanta_power
J 0
(-1450 3200);
DISPLAY INVISIBLE (-1450 3200);
FORCEPROP 1 LAST SIZE 1B
J 0
(-1375 3150);
DISPLAY 0.872340 (-1375 3150);
PAINT GREEN (-1375 3150);
DISPLAY INVISIBLE (-1375 3150);
FORCEPROP 1 LAST HDL_POWER GND
J 0
(-1450 3350);
DISPLAY 0.872340 (-1450 3350);
PAINT GREEN (-1450 3350);
DISPLAY INVISIBLE (-1450 3350);
FORCEPROP 1 LAST PATH I40
J 0
(-1375 3200);
DISPLAY 0.872340 (-1375 3200);
PAINT AQUA (-1375 3200);
DISPLAY INVISIBLE (-1375 3200);
FORCEADD OFFPAGE..2
(-325 3425);
FORCEPROP 2 LAST $XR0 173 
J 0
(-136 3425);
DISPLAY 0.638298 (-136 3425);
PAINT MONO (-136 3425);
FORCEPROP 2 LAST CDS_LIB standard
J 0
(-325 3425);
DISPLAY INVISIBLE (-325 3425);
FORCEPROP 1 LAST OFFPAGE TRUE
J 0
(0 3300);
DISPLAY 0.872340 (0 3300);
PAINT GREEN (0 3300);
DISPLAY INVISIBLE (0 3300);
FORCEPROP 1 LAST COMMENT_BODY TRUE
J 0
(-370 3330);
DISPLAY 0.872340 (-370 3330);
PAINT GREEN (-370 3330);
DISPLAY INVISIBLE (-370 3330);
FORCEPROP 2 LAST PATH I41
J 0
(-150 3500);
DISPLAY 1.021277 (-150 3500);
DISPLAY INVISIBLE (-150 3500);
FORCEADD Q_CAP..1
(-1000 3750);
FORCEPROP 1 LAST LOCATION C1523
J 0
(-900 3900);
DISPLAY 0.489362 (-900 3900);
PAINT SKYBLUE (-900 3900);
FORCEPROP 2 LAST $SEC 1
J 0
(-950 3950);
PAINT MONO (-950 3950);
DISPLAY INVISIBLE (-950 3950);
FORCEPROP 2 LAST CDS_SEC 1
J 0
(-950 3950);
PAINT MONO (-950 3950);
DISPLAY INVISIBLE (-950 3950);
FORCEPROP 1 LASTPIN (-1000 3850) $PN 1
J 0
(-990 3830);
DISPLAY 0.489362 (-990 3830);
PAINT GREEN (-990 3830);
FORCEPROP 1 LASTPIN (-1000 3650) $PN 2
J 0
(-990 3630);
DISPLAY 0.489362 (-990 3630);
PAINT GREEN (-990 3630);
FORCEPROP 1 LAST PACK_TYPE C0402
J 0
(-900 3600);
DISPLAY 0.489362 (-900 3600);
PAINT SKYBLUE (-900 3600);
FORCEPROP 1 LAST VOLTAGE 16V
J 0
(-900 3800);
DISPLAY 0.489362 (-900 3800);
PAINT SKYBLUE (-900 3800);
FORCEPROP 1 LAST VALUE 0.1UF
J 0
(-900 3850);
DISPLAY 0.489362 (-900 3850);
PAINT SKYBLUE (-900 3850);
FORCEPROP 1 LAST TOLERANCE 10%
J 0
(-900 3750);
DISPLAY 0.489362 (-900 3750);
PAINT SKYBLUE (-900 3750);
FORCEPROP 1 LAST MATERIAL X7R
J 0
(-900 3700);
DISPLAY 0.489362 (-900 3700);
PAINT SKYBLUE (-900 3700);
FORCEPROP 2 LAST CDS_LIB pure_quanta
J 0
(-1000 3750);
DISPLAY INVISIBLE (-1000 3750);
FORCEPROP 1 LAST PATH I42
J 0
(-950 3900);
DISPLAY 0.978723 (-950 3900);
PAINT WHITE (-950 3900);
DISPLAY INVISIBLE (-950 3900);
FORCEPROP 1 LAST PART_NUMBER CH4103K1B08
J 0
(-900 3650);
DISPLAY 0.489362 (-900 3650);
PAINT SKYBLUE (-900 3650);
DISPLAY INVISIBLE (-900 3650);
FORCEADD GND..1
(-1000 3550);
FORCEPROP 3 LASTPIN (-1000 3600) SIG_NAME GND\g
J 0
(-990 3610);
DISPLAY 0.659574 (-990 3610);
PAINT MONO (-990 3610);
DISPLAY INVISIBLE (-990 3610);
FORCEPROP 1 LAST SIZE 1B
J 0
(-925 3500);
DISPLAY 0.872340 (-925 3500);
PAINT GREEN (-925 3500);
DISPLAY INVISIBLE (-925 3500);
FORCEPROP 2 LAST CDS_LIB pure_quanta_power
J 0
(-1000 3550);
DISPLAY INVISIBLE (-1000 3550);
FORCEPROP 1 LAST HDL_POWER GND
J 0
(-1000 3700);
DISPLAY 0.872340 (-1000 3700);
PAINT GREEN (-1000 3700);
DISPLAY INVISIBLE (-1000 3700);
FORCEPROP 1 LAST PATH I43
J 0
(-925 3550);
DISPLAY 0.872340 (-925 3550);
PAINT AQUA (-925 3550);
DISPLAY INVISIBLE (-925 3550);
FORCEADD UNIVERSAL_POWER..1
(-1225 4025);
FORCEPROP 3 LASTPIN (-1225 3975) SIG_NAME PVDD18_S5_P0\g
J 0
(-1215 3985);
DISPLAY 0.659574 (-1215 3985);
PAINT MONO (-1215 3985);
DISPLAY INVISIBLE (-1215 3985);
FORCEPROP 1 LAST HDL_POWER PVDD18_S5_P0
J 1
(-1225 4075);
DISPLAY 0.489362 (-1225 4075);
PAINT GREEN (-1225 4075);
FORCEPROP 2 LAST CDS_LIB pure_quanta_power
J 0
(-1225 4025);
PAINT MONO (-1225 4025);
DISPLAY INVISIBLE (-1225 4025);
FORCEPROP 1 LAST PATH I44
J 0
(-1175 4050);
DISPLAY 0.872340 (-1175 4050);
PAINT AQUA (-1175 4050);
DISPLAY INVISIBLE (-1175 4050);
FORCEADD MOSFET_N..1
(-7650 5075);
FORCEPROP 1 LAST LOCATION Q63
J 0
(-7500 4970);
DISPLAY 0.489362 (-7500 4970);
PAINT SKYBLUE (-7500 4970);
FORCEPROP 0 LAST $SEC 1
J 0
(-7500 5175);
DISPLAY 0.680851 (-7500 5175);
PAINT MONO (-7500 5175);
DISPLAY INVISIBLE (-7500 5175);
FORCEPROP 0 LAST CDS_SEC 1
J 0
(-7525 5275);
DISPLAY 1.021277 (-7525 5275);
DISPLAY INVISIBLE (-7525 5275);
FORCEPROP 1 LASTPIN (-7600 5175) $PN D
R 1
J 0
(-7600 5168);
DISPLAY 0.489362 (-7600 5168);
PAINT MONO (-7600 5168);
FORCEPROP 1 LASTPIN (-7750 4975) $PN G
J 2
(-7740 4978);
DISPLAY 0.489362 (-7740 4978);
PAINT MONO (-7740 4978);
FORCEPROP 1 LASTPIN (-7600 4875) $PN S
R 1
J 2
(-7600 4888);
DISPLAY 0.489362 (-7600 4888);
PAINT MONO (-7600 4888);
FORCEPROP 1 LAST MATERIAL IC
J 0
(-7500 4810);
DISPLAY 0.489362 (-7500 4810);
PAINT SKYBLUE (-7500 4810);
FORCEPROP 1 LAST VALUE BSS138K
J 0
(-7500 5050);
DISPLAY 0.489362 (-7500 5050);
PAINT SKYBLUE (-7500 5050);
FORCEPROP 2 LAST PART_TYPE SMLF
J 0
(-7500 5125);
PAINT MONO (-7500 5125);
FORCEPROP 1 LAST PACK_TYPE SMLF
J 0
(-7625 4825);
DISPLAY 0.723404 (-7625 4825);
PAINT SKYBLUE (-7625 4825);
DISPLAY INVISIBLE (-7625 4825);
FORCEPROP 2 LAST CDS_LIB pure_quanta
J 0
(-7650 5075);
DISPLAY INVISIBLE (-7650 5075);
FORCEPROP 1 LAST CDS_LMAN_SYM_OUTLINE -50,50,100,-150
J 0
(-7650 5075);
DISPLAY 0.468085 (-7650 5075);
PAINT GREEN (-7650 5075);
DISPLAY INVISIBLE (-7650 5075);
FORCEPROP 0 LAST MANUF_PN BSS138K
J 0
(-7525 5325);
DISPLAY 1.021277 (-7525 5325);
DISPLAY INVISIBLE (-7525 5325);
FORCEPROP 0 LAST PATH I45
J 0
(-7525 5275);
DISPLAY 1.021277 (-7525 5275);
DISPLAY INVISIBLE (-7525 5275);
FORCEPROP 1 LAST PART_NUMBER BAM138K0000
J 0
(-7500 4890);
DISPLAY 0.489362 (-7500 4890);
PAINT SKYBLUE (-7500 4890);
DISPLAY INVISIBLE (-7500 4890);
FORCEADD MOSFET_N..1
(-4600 3150);
FORCEPROP 1 LAST LOCATION Q64
J 0
(-4475 3060);
DISPLAY 0.489362 (-4475 3060);
PAINT SKYBLUE (-4475 3060);
FORCEPROP 0 LAST $SEC 1
J 0
(-4475 3250);
DISPLAY 0.680851 (-4475 3250);
PAINT MONO (-4475 3250);
DISPLAY INVISIBLE (-4475 3250);
FORCEPROP 0 LAST CDS_SEC 1
J 0
(-4475 3350);
DISPLAY 1.021277 (-4475 3350);
DISPLAY INVISIBLE (-4475 3350);
FORCEPROP 1 LASTPIN (-4550 3250) $PN D
R 1
J 0
(-4550 3243);
DISPLAY 0.489362 (-4550 3243);
PAINT MONO (-4550 3243);
FORCEPROP 1 LASTPIN (-4700 3050) $PN G
J 2
(-4690 3053);
DISPLAY 0.489362 (-4690 3053);
PAINT MONO (-4690 3053);
FORCEPROP 1 LASTPIN (-4550 2950) $PN S
R 1
J 2
(-4550 2963);
DISPLAY 0.489362 (-4550 2963);
PAINT MONO (-4550 2963);
FORCEPROP 1 LAST VALUE BSS138K
J 0
(-4475 3140);
DISPLAY 0.489362 (-4475 3140);
PAINT SKYBLUE (-4475 3140);
FORCEPROP 1 LAST MATERIAL IC
J 0
(-4475 2900);
DISPLAY 0.489362 (-4475 2900);
PAINT SKYBLUE (-4475 2900);
FORCEPROP 2 LAST PART_TYPE SMLF
J 0
(-4475 3200);
PAINT MONO (-4475 3200);
FORCEPROP 1 LAST PACK_TYPE SMLF
J 0
(-4575 2900);
DISPLAY 0.723404 (-4575 2900);
PAINT SKYBLUE (-4575 2900);
DISPLAY INVISIBLE (-4575 2900);
FORCEPROP 1 LAST CDS_LMAN_SYM_OUTLINE -50,50,100,-150
J 0
(-4600 3150);
DISPLAY 0.468085 (-4600 3150);
PAINT GREEN (-4600 3150);
DISPLAY INVISIBLE (-4600 3150);
FORCEPROP 2 LAST CDS_LIB pure_quanta
J 0
(-4600 3150);
DISPLAY INVISIBLE (-4600 3150);
FORCEPROP 0 LAST MANUF_PN BSS138K
J 0
(-4475 3400);
DISPLAY 1.021277 (-4475 3400);
DISPLAY INVISIBLE (-4475 3400);
FORCEPROP 0 LAST PATH I46
J 0
(-4475 3350);
DISPLAY 1.021277 (-4475 3350);
DISPLAY INVISIBLE (-4475 3350);
FORCEPROP 1 LAST PART_NUMBER BAM138K0000
J 0
(-4475 2980);
DISPLAY 0.489362 (-4475 2980);
PAINT SKYBLUE (-4475 2980);
DISPLAY INVISIBLE (-4475 2980);
FORCEADD OFFPAGE..1
(-8925 4975);
FORCEPROP 2 LAST $XR0 81 
J 0
(-9176 4975);
DISPLAY 0.638298 (-9176 4975);
PAINT MONO (-9176 4975);
FORCEPROP 2 LAST CDS_LIB standard
J 0
(-8925 4975);
DISPLAY INVISIBLE (-8925 4975);
FORCEPROP 1 LAST OFFPAGE TRUE
J 0
(-8600 4850);
DISPLAY 0.872340 (-8600 4850);
PAINT GREEN (-8600 4850);
DISPLAY INVISIBLE (-8600 4850);
FORCEPROP 1 LAST COMMENT_BODY TRUE
J 0
(-8800 4875);
DISPLAY 0.872340 (-8800 4875);
PAINT GREEN (-8800 4875);
DISPLAY INVISIBLE (-8800 4875);
FORCEPROP 2 LAST PATH I47
J 0
(-9175 5025);
DISPLAY 1.021277 (-9175 5025);
DISPLAY INVISIBLE (-9175 5025);
FORCEADD Q_RES..1
(-6050 4950);
FORCEPROP 1 LAST LOCATION R6104
J 0
(-5925 4950);
DISPLAY 0.489362 (-5925 4950);
PAINT SKYBLUE (-5925 4950);
FORCEPROP 0 LAST $SEC 1
J 0
(-5925 5000);
DISPLAY 0.680851 (-5925 5000);
PAINT MONO (-5925 5000);
DISPLAY INVISIBLE (-5925 5000);
FORCEPROP 0 LAST CDS_SEC 1
J 0
(-5925 5000);
DISPLAY 0.680851 (-5925 5000);
DISPLAY INVISIBLE (-5925 5000);
FORCEPROP 1 LASTPIN (-6150 4950) $PN 1
J 0
(-6138 4962);
DISPLAY 0.489362 (-6138 4962);
PAINT MONO (-6138 4962);
FORCEPROP 1 LASTPIN (-5950 4950) $PN 2
J 0
(-5988 4962);
DISPLAY 0.489362 (-5988 4962);
PAINT MONO (-5988 4962);
FORCEPROP 1 LAST VALUE 0
J 2
(-6175 4950);
DISPLAY 0.489362 (-6175 4950);
PAINT SKYBLUE (-6175 4950);
FORCEPROP 2 LAST CDS_LIB pure_quanta
J 0
(-6050 4950);
DISPLAY INVISIBLE (-6050 4950);
FORCEPROP 2 LAST BOM_COST MEM
J 2
(-6025 5100);
DISPLAY 0.744681 (-6025 5100);
PAINT WHITE (-6025 5100);
DISPLAY INVISIBLE (-6025 5100);
FORCEPROP 1 LAST WATTAGE 1/16W
J 2
(-6125 4875);
DISPLAY 0.489362 (-6125 4875);
PAINT SKYBLUE (-6125 4875);
DISPLAY INVISIBLE (-6125 4875);
FORCEPROP 1 LAST MATERIAL CHIP
J 2
(-5875 4925);
DISPLAY 0.489362 (-5875 4925);
PAINT SKYBLUE (-5875 4925);
DISPLAY INVISIBLE (-5875 4925);
FORCEPROP 1 LAST TOLERANCE 5%
J 0
(-6175 4925);
DISPLAY 0.489362 (-6175 4925);
PAINT SKYBLUE (-6175 4925);
DISPLAY INVISIBLE (-6175 4925);
FORCEPROP 1 LAST PACK_TYPE 0402LF
J 2
(-5875 4875);
DISPLAY 0.489362 (-5875 4875);
PAINT SKYBLUE (-5875 4875);
DISPLAY INVISIBLE (-5875 4875);
FORCEPROP 1 LAST PATH I48
J 0
(-6100 5100);
DISPLAY 0.978723 (-6100 5100);
PAINT WHITE (-6100 5100);
DISPLAY INVISIBLE (-6100 5100);
FORCEPROP 1 LAST PART_NUMBER CS00002JB13
J 2
(-5925 4875);
DISPLAY 0.489362 (-5925 4875);
PAINT SKYBLUE (-5925 4875);
DISPLAY INVISIBLE (-5925 4875);
FORCEADD Q_RES..1
(-4225 4425);
FORCEPROP 1 LAST LOCATION R6105
J 0
(-4525 4425);
DISPLAY 0.489362 (-4525 4425);
PAINT SKYBLUE (-4525 4425);
FORCEPROP 0 LAST $SEC 1
J 0
(-4100 4475);
DISPLAY 0.680851 (-4100 4475);
PAINT MONO (-4100 4475);
DISPLAY INVISIBLE (-4100 4475);
FORCEPROP 0 LAST CDS_SEC 1
J 0
(-4100 4475);
DISPLAY 0.680851 (-4100 4475);
DISPLAY INVISIBLE (-4100 4475);
FORCEPROP 1 LASTPIN (-4325 4425) $PN 1
J 0
(-4313 4437);
DISPLAY 0.489362 (-4313 4437);
PAINT MONO (-4313 4437);
FORCEPROP 1 LASTPIN (-4125 4425) $PN 2
J 0
(-4163 4437);
DISPLAY 0.489362 (-4163 4437);
PAINT MONO (-4163 4437);
FORCEPROP 1 LAST VALUE 0
J 2
(-4350 4425);
DISPLAY 0.489362 (-4350 4425);
PAINT SKYBLUE (-4350 4425);
FORCEPROP 1 LAST PACK_TYPE 0402LF
J 2
(-4050 4350);
DISPLAY 0.489362 (-4050 4350);
PAINT SKYBLUE (-4050 4350);
DISPLAY INVISIBLE (-4050 4350);
FORCEPROP 1 LAST TOLERANCE 5%
J 0
(-4350 4400);
DISPLAY 0.489362 (-4350 4400);
PAINT SKYBLUE (-4350 4400);
DISPLAY INVISIBLE (-4350 4400);
FORCEPROP 1 LAST MATERIAL CHIP
J 2
(-4050 4400);
DISPLAY 0.489362 (-4050 4400);
PAINT SKYBLUE (-4050 4400);
DISPLAY INVISIBLE (-4050 4400);
FORCEPROP 1 LAST WATTAGE 1/16W
J 2
(-4300 4350);
DISPLAY 0.489362 (-4300 4350);
PAINT SKYBLUE (-4300 4350);
DISPLAY INVISIBLE (-4300 4350);
FORCEPROP 2 LAST BOM_COST MEM
J 2
(-4200 4575);
DISPLAY 0.744681 (-4200 4575);
PAINT WHITE (-4200 4575);
DISPLAY INVISIBLE (-4200 4575);
FORCEPROP 2 LAST CDS_LIB pure_quanta
J 0
(-4225 4425);
DISPLAY INVISIBLE (-4225 4425);
FORCEPROP 1 LAST PATH I49
J 0
(-4275 4575);
DISPLAY 0.978723 (-4275 4575);
PAINT WHITE (-4275 4575);
DISPLAY INVISIBLE (-4275 4575);
FORCEPROP 1 LAST PART_NUMBER CS00002JB13
J 2
(-3925 4325);
DISPLAY 0.489362 (-3925 4325);
PAINT SKYBLUE (-3925 4325);
DISPLAY INVISIBLE (-3925 4325);
FORCEADD OFFPAGE..2
(-4250 5825);
FORCEPROP 2 LAST $XR0 27 
J 0
(-4061 5825);
DISPLAY 0.638298 (-4061 5825);
PAINT MONO (-4061 5825);
FORCEPROP 2 LAST CDS_LIB standard
J 0
(-4250 5825);
PAINT MONO (-4250 5825);
DISPLAY INVISIBLE (-4250 5825);
FORCEPROP 1 LAST OFFPAGE TRUE
J 0
(-3925 5700);
DISPLAY 0.872340 (-3925 5700);
PAINT GREEN (-3925 5700);
DISPLAY INVISIBLE (-3925 5700);
FORCEPROP 1 LAST COMMENT_BODY TRUE
J 0
(-4295 5730);
DISPLAY 0.872340 (-4295 5730);
PAINT GREEN (-4295 5730);
DISPLAY INVISIBLE (-4295 5730);
FORCEPROP 2 LAST PATH I5
J 0
(-4050 5875);
DISPLAY 1.021277 (-4050 5875);
DISPLAY INVISIBLE (-4050 5875);
FORCEADD Q_RES..1
(-950 3425);
FORCEPROP 1 LAST LOCATION R6110
J 0
(-1000 3475);
DISPLAY 0.489362 (-1000 3475);
PAINT SKYBLUE (-1000 3475);
FORCEPROP 0 LAST $SEC 1
J 0
(-1000 3500);
DISPLAY 0.680851 (-1000 3500);
PAINT MONO (-1000 3500);
DISPLAY INVISIBLE (-1000 3500);
FORCEPROP 0 LAST CDS_SEC 1
J 0
(-1000 3500);
DISPLAY 0.680851 (-1000 3500);
DISPLAY INVISIBLE (-1000 3500);
FORCEPROP 1 LASTPIN (-1050 3425) $PN 1
J 0
(-1038 3437);
DISPLAY 0.787234 (-1038 3437);
PAINT MONO (-1038 3437);
FORCEPROP 1 LASTPIN (-850 3425) $PN 2
J 0
(-888 3437);
DISPLAY 0.787234 (-888 3437);
PAINT MONO (-888 3437);
FORCEPROP 1 LAST MATERIAL CHIP
J 0
(-875 3400);
DISPLAY 0.489362 (-875 3400);
PAINT SKYBLUE (-875 3400);
FORCEPROP 1 LAST VALUE 0
J 2
(-800 3425);
DISPLAY 0.489362 (-800 3425);
PAINT SKYBLUE (-800 3425);
FORCEPROP 2 LAST CDS_LIB pure_quanta
J 0
(-950 3425);
DISPLAY INVISIBLE (-950 3425);
FORCEPROP 1 LAST PACK_TYPE 0402LF
J 0
(-700 3275);
DISPLAY 0.978723 (-700 3275);
PAINT SKYBLUE (-700 3275);
DISPLAY INVISIBLE (-700 3275);
FORCEPROP 1 LAST TOLERANCE 5%
J 0
(-950 3325);
DISPLAY 0.978723 (-950 3325);
PAINT SKYBLUE (-950 3325);
DISPLAY INVISIBLE (-950 3325);
FORCEPROP 1 LAST WATTAGE 1/16W
J 2
(-975 3275);
DISPLAY 0.978723 (-975 3275);
PAINT SKYBLUE (-975 3275);
DISPLAY INVISIBLE (-975 3275);
FORCEPROP 1 LAST PATH I50
J 0
(-1000 3575);
DISPLAY 0.978723 (-1000 3575);
PAINT WHITE (-1000 3575);
DISPLAY INVISIBLE (-1000 3575);
FORCEPROP 1 LAST PART_NUMBER CS00002JB13
J 0
(-1000 3525);
DISPLAY 0.978723 (-1000 3525);
PAINT SKYBLUE (-1000 3525);
DISPLAY INVISIBLE (-1000 3525);
FORCEADD OFFPAGE..1
(-7575 5875);
FORCEPROP 2 LAST $XR0 173 
J 0
(-7857 5875);
DISPLAY 0.638298 (-7857 5875);
PAINT MONO (-7857 5875);
FORCEPROP 2 LAST CDS_LIB standard
J 0
(-7575 5875);
DISPLAY INVISIBLE (-7575 5875);
FORCEPROP 1 LAST OFFPAGE TRUE
J 0
(-7250 5750);
DISPLAY 0.872340 (-7250 5750);
PAINT GREEN (-7250 5750);
DISPLAY INVISIBLE (-7250 5750);
FORCEPROP 1 LAST COMMENT_BODY TRUE
J 0
(-7450 5775);
DISPLAY 0.872340 (-7450 5775);
PAINT GREEN (-7450 5775);
DISPLAY INVISIBLE (-7450 5775);
FORCEPROP 2 LAST PATH I6
J 0
(-7525 5950);
DISPLAY 1.021277 (-7525 5950);
DISPLAY INVISIBLE (-7525 5950);
FORCEADD UNIVERSAL_POWER..1
(-8200 5575);
FORCEPROP 3 LASTPIN (-8200 5525) SIG_NAME PVDD18_S5_P0\g
J 0
(-8190 5535);
DISPLAY 0.659574 (-8190 5535);
PAINT MONO (-8190 5535);
DISPLAY INVISIBLE (-8190 5535);
FORCEPROP 1 LAST HDL_POWER PVDD18_S5_P0
J 1
(-8200 5625);
DISPLAY 0.489362 (-8200 5625);
PAINT GREEN (-8200 5625);
FORCEPROP 2 LAST CDS_LIB pure_quanta_power
J 0
(-8200 5575);
PAINT MONO (-8200 5575);
DISPLAY INVISIBLE (-8200 5575);
FORCEPROP 1 LAST PATH I9
J 0
(-8150 5600);
DISPLAY 0.872340 (-8150 5600);
PAINT AQUA (-8150 5600);
DISPLAY INVISIBLE (-8150 5600);
FORCEADD CAD_NOTE..1
(-4375 4225);
FORCEPROP 0 LAST L1 R6105 PLACE CLOSE TO U13
J 0
(-4525 4100);
DISPLAY 0.617021 (-4525 4100);
PAINT WHITE (-4525 4100);
FORCEPROP 2 LAST CDS_LIB pure_quanta_power
J 0
(-4375 4225);
DISPLAY INVISIBLE (-4375 4225);
FORCEPROP 1 LAST COMMENT_BODY TRUE
J 0
(-4350 4325);
DISPLAY 0.574468 (-4350 4325);
PAINT WHITE (-4350 4325);
DISPLAY INVISIBLE (-4350 4325);
FORCEADD CAD_NOTE..1
(-975 3200);
FORCEPROP 0 LAST L1 R6110 PLACE CLOSE TO U154
J 0
(-1125 3075);
DISPLAY 0.617021 (-1125 3075);
PAINT WHITE (-1125 3075);
FORCEPROP 2 LAST CDS_LIB pure_quanta_power
J 0
(-975 3200);
DISPLAY INVISIBLE (-975 3200);
FORCEPROP 1 LAST COMMENT_BODY TRUE
J 0
(-950 3300);
DISPLAY 0.574468 (-950 3300);
PAINT WHITE (-950 3300);
DISPLAY INVISIBLE (-950 3300);
FORCEADD DNS..1
(-4925 5600);
PAINT RED (-4925 5600);
FORCEPROP 2 LAST CDS_LIB mstr_misc
J 0
(-4925 5600);
DISPLAY INVISIBLE (-4925 5600);
FORCEPROP 1 LAST COMMENT_BODY TRUE
R 1
J 0
(-4850 5375);
DISPLAY 0.872340 (-4850 5375);
PAINT GREEN (-4850 5375);
DISPLAY INVISIBLE (-4850 5375);
FORCEADD QUANTA_TITLE_BLOCK_C..1
(0 0);
FORCEPROP 0 LAST CDS_CON_LAST_MODIFIED Thu Sep 14 16:12:16 2023
J 0
(-1885 15);
DISPLAY INVISIBLE (-1885 15);
FORCEPROP 1 LAST CUSTOM_TXT_CDS <CON_LAST_MODIFIED>
J 0
(-1885 15);
DISPLAY 0.978723 (-1885 15);
FORCEPROP 2 LAST CUSTOM_TXT_CDS <XR_PAGE_TITLE>
J 0
(-7890 5250);
DISPLAY 0.638298 (-7890 5250);
PAINT PINK (-7890 5250);
DISPLAY INVISIBLE (-7890 5250);
FORCEPROP 1 LAST CUSTOM_TXT_CDS <NAME_2>
J 0
(-3175 50);
FORCEPROP 1 LAST CUSTOM_TXT_CDS <NAME_1>
J 0
(-3175 175);
FORCEPROP 1 LAST CUSTOM_TXT_CDS <Q_NUMBER>
J 0
(-1403 103);
DISPLAY 1.212766 (-1403 103);
FORCEPROP 1 LAST CUSTOM_TXT_CDS <Q_PROJ>
J 0
(-2382 102);
DISPLAY 1.212766 (-2382 102);
FORCEPROP 1 LAST CUSTOM_TXT_CDS <Q_REV>
J 0
(-184 103);
DISPLAY 1.212766 (-184 103);
FORCEPROP 1 LAST CUSTOM_TXT_CDS <CON_PAGE_NUM> OF <CON_TOTAL_PAGES>
J 0
(-446 18);
DISPLAY 0.978723 (-446 18);
FORCEPROP 1 LAST Q_TITLE JTAG - TDI/TDO
J 0
(-9300 50);
DISPLAY 2.446809 (-9300 50);
PAINT GREEN (-9300 50);
FORCEPROP 2 LAST CDS_LIB pure_quanta
J 0
(0 0);
DISPLAY INVISIBLE (0 0);
FORCEPROP 1 LAST CDS_LMAN_SYM_OUTLINE -9475,6775,100,-125
J 0
(0 0);
DISPLAY 0.468085 (0 0);
PAINT GREEN (0 0);
DISPLAY INVISIBLE (0 0);
FORCEPROP 2 LAST PAGE_BORDER TRUE
J 0
(-7890 5250);
DISPLAY 0.638298 (-7890 5250);
PAINT PINK (-7890 5250);
DISPLAY INVISIBLE (-7890 5250);
FORCEPROP 2 LAST CDS_XR_PAGE_TITLE CR-174 : @T6G_MB_LIB.T6G(SCH_1):PAGE174
J 0
(-7890 5250);
DISPLAY 0.638298 (-7890 5250);
PAINT PINK (-7890 5250);
DISPLAY INVISIBLE (-7890 5250);
FORCEPROP 1 LAST Q_DEPT BU9
J 1
(-3763 49);
DISPLAY 1.957447 (-3763 49);
PAINT GREEN (-3763 49);
DISPLAY INVISIBLE (-3763 49);
FORCEPROP 1 LAST COMMENT_BODY TRUE
J 0
(12 -13);
DISPLAY 0.978723 (12 -13);
PAINT GREEN (12 -13);
DISPLAY INVISIBLE (12 -13);
FORCEADD CAD_NOTE..1
(-5150 5050);
FORCEPROP 0 LAST L1 R6104 PLACE CLOSE TO U13
J 0
(-5300 4925);
DISPLAY 0.617021 (-5300 4925);
PAINT WHITE (-5300 4925);
FORCEPROP 2 LAST CDS_LIB pure_quanta_power
J 0
(-5150 5050);
DISPLAY INVISIBLE (-5150 5050);
FORCEPROP 1 LAST COMMENT_BODY TRUE
J 0
(-5125 5150);
DISPLAY 0.574468 (-5125 5150);
PAINT WHITE (-5125 5150);
DISPLAY INVISIBLE (-5125 5150);
WIRE 16 -1 (-7600 5650)(-7600 5600);
WIRE 16 -1 (-6075 5725)(-5975 5725);
WIRE 16 -1 (-5975 5725)(-5975 5650);
WIRE 16 -1 (-5725 6025)(-5725 5975);
WIRE 16 -1 (-7600 4875)(-7600 4700);
WIRE 16 -1 (-4000 4675)(-4000 4625);
WIRE 16 -1 (-4550 3675)(-4550 3625);
WIRE 16 -1 (-5225 3600)(-5225 3500);
WIRE 16 -1 (-4550 2950)(-4550 2775);
WIRE 16 -1 (-4900 5525)(-4900 5375);
WIRE 16 -1 (-2150 4625)(-2150 4575);
WIRE 16 -1 (-4675 4375)(-4575 4375);
WIRE 16 -1 (-4575 4375)(-4575 4300);
WIRE 16 -1 (-2825 4325)(-2725 4325);
WIRE 16 -1 (-2725 4325)(-2725 4250);
WIRE 16 -1 (-1550 3325)(-1450 3325);
WIRE 16 -1 (-1450 3325)(-1450 3250);
WIRE 16 -1 (-1000 3650)(-1000 3600);
WIRE 16 -1 (-8200 5525)(-8200 5425);
WIRE 16 -1 (-6825 5775)(-6675 5775);
WIRE 16 -1 (-6825 5875)(-6825 5775);
WIRE 16 -1 (-6825 5875)(-6675 5875);
WIRE 16 -1 (-7525 5875)(-6825 5875);
FORCEPROP 2 LAST SIG_NAME JTAG_CPUX_TDI
J 0
(-7335 5885);
DISPLAY 0.489362 (-7335 5885);
WIRE 16 -1 (-6375 4525)(-5275 4525);
FORCEPROP 2 LAST SIG_NAME JTAG_CPU0_TDO
J 0
(-6185 4535);
DISPLAY 0.489362 (-6185 4535);
WIRE 16 -1 (-1000 3850)(-1000 3925);
WIRE 16 -1 (-1000 3925)(-1225 3925);
WIRE 16 -1 (-1225 3975)(-1225 3925);
WIRE 16 -1 (-1225 3475)(-1225 3925);
WIRE 16 -1 (-1225 3475)(-1550 3475);
WIRE 16 -1 (-4000 4875)(-4000 4950);
WIRE 16 -1 (-4000 4950)(-4225 4950);
WIRE 16 -1 (-4225 5000)(-4225 4950);
WIRE 16 -1 (-4225 4525)(-4225 4950);
WIRE 16 -1 (-4225 4525)(-4675 4525);
WIRE 16 -1 (-5725 6225)(-5725 6300);
WIRE 16 -1 (-5725 6300)(-5950 6300);
WIRE 16 -1 (-5950 6350)(-5950 6300);
WIRE 16 -1 (-5950 5875)(-5950 6300);
WIRE 16 -1 (-6075 5875)(-5950 5875);
WIRE 16 -1 (-3025 3475)(-2150 3475);
FORCEPROP 2 LAST SIG_NAME JTAG_CPU1_TDO
J 0
(-2835 3485);
DISPLAY 0.489362 (-2835 3485);
WIRE 16 -1 (-5450 4950)(-5450 4425);
WIRE 16 -1 (-5950 4950)(-5450 4950);
FORCEPROP 2 LAST SIG_NAME JTAG_CPU0_BYPASS_R1
J 0
(-5760 4960);
DISPLAY 0.489362 (-5760 4960);
FORCEPROP 2 LASTPROP $XRERR UNIQUE?
J 0
(-6000 4960);
DISPLAY 0.638298 (-6000 4960);
PAINT MONO (-6000 4960);
DISPLAY INVISIBLE (-6000 4960);
WIRE 16 -1 (-5450 4425)(-5275 4425);
WIRE 16 -1 (-5450 5200)(-6250 5200);
WIRE 16 -1 (-5450 5775)(-5450 5200);
WIRE 16 -1 (-6250 5200)(-6250 4950);
WIRE 16 -1 (-6250 4950)(-6150 4950);
WIRE 16 -1 (-6075 5775)(-5450 5775);
FORCEPROP 2 LAST SIG_NAME JTAG_CPU0_BYPASS
J 0
(-5935 5785);
DISPLAY 0.489362 (-5935 5785);
FORCEPROP 2 LASTPROP $XRERR UNIQUE?
J 0
(-6175 5785);
DISPLAY 0.638298 (-6175 5785);
PAINT MONO (-6175 5785);
DISPLAY INVISIBLE (-6175 5785);
WIRE 16 -1 (-4075 4475)(-3825 4475);
FORCEPROP 2 LAST SIG_NAME JTAG_CPU0_TDO_CPU1_TDI
J 0
(-4035 4475);
DISPLAY 0.489362 (-4035 4475);
FORCEPROP 2 LASTPROP $XRERR UNIQUE?
J 0
(-4275 4475);
DISPLAY 0.638298 (-4275 4475);
PAINT MONO (-4275 4475);
DISPLAY INVISIBLE (-4275 4475);
WIRE 16 -1 (-4075 4475)(-4075 4425);
WIRE 16 -1 (-4675 4475)(-4075 4475);
WIRE 16 -1 (-3825 4475)(-3425 4475);
WIRE 16 -1 (-3825 4475)(-3825 4375);
WIRE 16 -1 (-3825 4375)(-3425 4375);
WIRE 16 -1 (-4075 4425)(-4125 4425);
WIRE 16 -1 (-4325 4425)(-4675 4425);
FORCEPROP 2 LAST SIG_NAME JTAG_CPU0_TDO_CPU1_TDI_R1
J 0
(-4560 4385);
DISPLAY 0.489362 (-4560 4385);
FORCEPROP 2 LASTPROP $XRERR UNIQUE?
J 0
(-4800 4385);
DISPLAY 0.638298 (-4800 4385);
PAINT MONO (-4800 4385);
DISPLAY INVISIBLE (-4800 4385);
WIRE 16 -1 (-850 3425)(-375 3425);
FORCEPROP 2 LAST SIG_NAME JTAG_CPUX_TDO
J 0
(-735 3435);
DISPLAY 0.489362 (-735 3435);
WIRE 16 -1 (-1100 3425)(-1100 3375);
WIRE 16 -1 (-1100 3425)(-1050 3425);
WIRE 16 -1 (-1550 3425)(-1100 3425);
FORCEPROP 2 LAST SIG_NAME JTAG_CPUX_TDO_R
J 0
(-1385 3435);
DISPLAY 0.489362 (-1385 3435);
FORCEPROP 2 LASTPROP $XRERR UNIQUE?
J 0
(-1625 3435);
DISPLAY 0.638298 (-1625 3435);
PAINT MONO (-1625 3435);
DISPLAY INVISIBLE (-1625 3435);
WIRE 16 -1 (-1100 3375)(-1550 3375);
WIRE 16 -1 (-8875 4975)(-8200 4975);
FORCEPROP 2 LAST SIG_NAME CPU0_HDT_BYPASS_SEL
J 0
(-8710 4985);
DISPLAY 0.489362 (-8710 4985);
WIRE 16 -1 (-8200 4975)(-8025 4975);
WIRE 16 -1 (-8200 5225)(-8200 4975);
WIRE 16 -1 (-8025 5825)(-8025 4975);
WIRE 16 -1 (-8025 4975)(-7750 4975);
WIRE 16 -1 (-6950 5825)(-8025 5825);
WIRE 16 -1 (-6675 5825)(-6950 5825);
WIRE 16 -1 (-6950 5825)(-6950 4475);
WIRE 16 -1 (-6950 4475)(-5275 4475);
WIRE 16 -1 (-6825 4375)(-5275 4375);
WIRE 16 -1 (-6825 5250)(-6825 4375);
WIRE 16 -1 (-6825 5250)(-6825 5725);
WIRE 16 -1 (-7600 5250)(-6825 5250);
FORCEPROP 2 LAST SIG_NAME FM_PLD_CPU0_PRSNT_HDT_N
J 0
(-7535 5260);
DISPLAY 0.489362 (-7535 5260);
FORCEPROP 2 LASTPROP $XRERR UNIQUE?
J 0
(-7775 5260);
DISPLAY 0.638298 (-7775 5260);
PAINT MONO (-7775 5260);
DISPLAY INVISIBLE (-7775 5260);
WIRE 16 -1 (-7600 5400)(-7600 5250);
WIRE 16 -1 (-7600 5250)(-7600 5175);
WIRE 16 -1 (-6825 5725)(-6675 5725);
WIRE 16 -1 (-5225 3050)(-5050 3050);
WIRE 16 -1 (-5225 3300)(-5225 3050);
WIRE 16 -1 (-5225 3050)(-6075 3050);
FORCEPROP 2 LAST SIG_NAME CPU1_HDT_BYPASS_SEL
J 0
(-5875 3060);
DISPLAY 0.489362 (-5875 3060);
WIRE 16 -1 (-5050 3950)(-5050 3050);
WIRE 16 -1 (-5050 3050)(-4700 3050);
WIRE 16 -1 (-5050 3950)(-3650 3950);
WIRE 16 -1 (-3650 4425)(-3650 3950);
WIRE 16 -1 (-3650 3950)(-3650 3425);
WIRE 16 -1 (-3650 3425)(-2150 3425);
WIRE 16 -1 (-3650 4425)(-3425 4425);
WIRE 16 -1 (-4550 3325)(-3825 3325);
WIRE 16 -1 (-4550 3425)(-4550 3325);
WIRE 16 -1 (-4550 3325)(-4550 3250);
WIRE 16 -1 (-3825 4325)(-3825 3325);
WIRE 16 -1 (-2150 3325)(-3825 3325);
FORCEPROP 2 LAST SIG_NAME FM_PLD_CPU1_PRSNT_HDT_N
J 0
(-3785 3335);
DISPLAY 0.489362 (-3785 3335);
FORCEPROP 2 LASTPROP $XRERR UNIQUE?
J 0
(-4025 3335);
DISPLAY 0.638298 (-4025 3335);
PAINT MONO (-4025 3335);
DISPLAY INVISIBLE (-4025 3335);
WIRE 16 -1 (-3825 4325)(-3425 4325);
WIRE 16 -1 (-5125 5825)(-4900 5825);
WIRE 16 -1 (-4300 5825)(-4900 5825);
FORCEPROP 2 LAST SIG_NAME JTAG_CPU0_TDI
J 0
(-4785 5835);
DISPLAY 0.489362 (-4785 5835);
WIRE 16 -1 (-4900 5725)(-4900 5825);
WIRE 16 -1 (-6075 5825)(-5325 5825);
FORCEPROP 2 LAST SIG_NAME JTAG_CPU0_R_TDI
J 0
(-5935 5835);
DISPLAY 0.489362 (-5935 5835);
FORCEPROP 2 LASTPROP $XRERR UNIQUE?
J 0
(-6175 5835);
DISPLAY 0.638298 (-6175 5835);
PAINT MONO (-6175 5835);
DISPLAY INVISIBLE (-6175 5835);
WIRE 16 -1 (-2825 4425)(-2075 4425);
FORCEPROP 2 LAST SIG_NAME JTAG_CPU1_R_TDI
J 0
(-2685 4435);
DISPLAY 0.489362 (-2685 4435);
FORCEPROP 2 LASTPROP $XRERR UNIQUE?
J 0
(-2925 4435);
DISPLAY 0.638298 (-2925 4435);
PAINT MONO (-2925 4435);
DISPLAY INVISIBLE (-2925 4435);
WIRE 16 -1 (-1875 4425)(-1050 4425);
FORCEPROP 2 LAST SIG_NAME JTAG_CPU1_TDI
J 0
(-1535 4435);
DISPLAY 0.489362 (-1535 4435);
WIRE 16 -1 (-2825 4375)(-2225 4375);
FORCEPROP 2 LAST SIG_NAME JTAG_CPU1_BYPASS
J 0
(-2685 4385);
DISPLAY 0.489362 (-2685 4385);
FORCEPROP 2 LASTPROP $XRERR UNIQUE?
J 0
(-2925 4385);
DISPLAY 0.638298 (-2925 4385);
PAINT MONO (-2925 4385);
DISPLAY INVISIBLE (-2925 4385);
WIRE 16 -1 (-2225 4375)(-2225 3375);
WIRE 16 -1 (-2225 3375)(-2150 3375);
WIRE 16 -1 (-2375 4475)(-2375 4900);
WIRE 16 -1 (-2375 4475)(-2825 4475);
WIRE 16 -1 (-2150 4900)(-2375 4900);
WIRE 16 -1 (-2375 4950)(-2375 4900);
WIRE 16 -1 (-2150 4825)(-2150 4900);
DOT 1 (-1100 3425);
DOT 1 (-4075 4475);
DOT 1 (-5225 3050);
DOT 1 (-8200 4975);
DOT 1 (-6825 5250);
DOT 1 (-4225 4950);
DOT 1 (-2375 4900);
DOT 1 (-3825 4475);
DOT 1 (-1225 3925);
DOT 1 (-3650 3950);
DOT 1 (-3825 3325);
DOT 1 (-5950 6300);
DOT 1 (-4900 5825);
DOT 1 (-6825 5875);
DOT 1 (-6950 5825);
DOT 1 (-7600 5250);
DOT 1 (-4550 3325);
DOT 1 (-5050 3050);
DOT 1 (-8025 4975);
FORCENOTE
CPU0 TDO
(-6575 4625) 0;
DISPLAY LEFT (-6575 4625);
DISPLAY 2.510638 (-6575 4625);
PAINT WHITE (-6575 4625);
FORCENOTE
L:BYPASS
(-8825 4600) 0;
DISPLAY LEFT (-8825 4600);
DISPLAY 2.510638 (-8825 4600);
PAINT WHITE (-8825 4600);
FORCENOTE
L:BYPASS
(-6025 2625) 0;
DISPLAY LEFT (-6025 2625);
DISPLAY 2.510638 (-6025 2625);
PAINT WHITE (-6025 2625);
FORCENOTE
H:CPU0
(-8825 4750) 0;
DISPLAY LEFT (-8825 4750);
DISPLAY 2.510638 (-8825 4750);
PAINT WHITE (-8825 4750);
FORCENOTE
CPU1 TDO
(-3225 3575) 0;
DISPLAY LEFT (-3225 3575);
DISPLAY 2.510638 (-3225 3575);
PAINT WHITE (-3225 3575);
FORCENOTE
H:CPU1
(-6025 2775) 0;
DISPLAY LEFT (-6025 2775);
DISPLAY 2.510638 (-6025 2775);
PAINT WHITE (-6025 2775);
FORCENOTE
CPU0 TDI
(-5000 5975) 0;
DISPLAY LEFT (-5000 5975);
DISPLAY 2.510638 (-5000 5975);
PAINT WHITE (-5000 5975);
FORCENOTE
CPU1 TDI
(-1575 4550) 0;
DISPLAY LEFT (-1575 4550);
DISPLAY 2.510638 (-1575 4550);
PAINT WHITE (-1575 4550);
QUIT
